G04 ================== begin FILE IDENTIFICATION RECORD ==================*
G04 Layout Name:  D:/<user>/Wistron_project/16347-sc/gbr/16347-sc.brd*
G04 Film Name:    BSMD*
G04 File Format:  Gerber RS274X*
G04 File Origin:  Cadence Allegro 16.5-S056*
G04 Origin Date:  Tue Mar 14 17:08:16 2017*
G04 *
G04 Layer:  VIA CLASS/PASTEMASK_BOTTOM*
G04 Layer:  PIN/PASTEMASK_BOTTOM*
G04 Layer:  PACKAGE GEOMETRY/PASTEMASK_BOTTOM*
G04 Layer:  DRAWING FORMAT/LAYER_PCB_STORY*
G04 Layer:  DRAWING FORMAT/LAYER_PAST_B*
G04 Layer:  BOARD GEOMETRY/PANEL_OUTLINE*
G04 *
G04 Offset:    (0.00 0.00)*
G04 Mirror:    No*
G04 Mode:      Positive*
G04 Rotation:  0*
G04 FullContactRelief:  No*
G04 UndefLineWidth:     6.00*
G04 ================== end FILE IDENTIFICATION RECORD ====================*
%FSLAX35Y35*MOIN*%
%IR0*IPPOS*OFA0.00000B0.00000*MIA0B0*SFA1.00000B1.00000*%
%AMMACRO19*
4,1,40,.013,-.017,
-.013,-.017,
-.013695,-.016939,
-.014368,-.016759,
-.015,-.016464,
-.015571,-.016064,
-.016064,-.015571,
-.016464,-.015,
-.016759,-.014368,
-.016939,-.013695,
-.017,-.013,
-.017,.013,
-.016939,.013695,
-.016759,.014368,
-.016464,.015,
-.016064,.015571,
-.015571,.016064,
-.015,.016464,
-.014368,.016759,
-.013695,.016939,
-.013,.017,
.013,.017,
.013695,.016939,
.014368,.016759,
.015,.016464,
.015571,.016064,
.016064,.015571,
.016464,.015,
.016759,.014368,
.016939,.013695,
.017,.013,
.017,-.013,
.016939,-.013695,
.016759,-.014368,
.016464,-.015,
.016064,-.015571,
.015571,-.016064,
.015,-.016464,
.014368,-.016759,
.013695,-.016939,
.013,-.017,
0.0*
%
%ADD19MACRO19*%
%AMMACRO14*
4,1,40,-.017,-.013,
-.017,.013,
-.016939,.013695,
-.016759,.014368,
-.016464,.015,
-.016064,.015571,
-.015571,.016064,
-.015,.016464,
-.014368,.016759,
-.013695,.016939,
-.013,.017,
.013,.017,
.013695,.016939,
.014368,.016759,
.015,.016464,
.015571,.016064,
.016064,.015571,
.016464,.015,
.016759,.014368,
.016939,.013695,
.017,.013,
.017,-.013,
.016939,-.013695,
.016759,-.014368,
.016464,-.015,
.016064,-.015571,
.015571,-.016064,
.015,-.016464,
.014368,-.016759,
.013695,-.016939,
.013,-.017,
-.013,-.017,
-.013695,-.016939,
-.014368,-.016759,
-.015,-.016464,
-.015571,-.016064,
-.016064,-.015571,
-.016464,-.015,
-.016759,-.014368,
-.016939,-.013695,
-.017,-.013,
0.0*
%
%ADD14MACRO14*%
%ADD10C,.04*%
%ADD15C,.024*%
%AMMACRO13*
4,1,40,.007,-.0225,
.008389,-.022378,
.009736,-.022018,
.011,-.021428,
.012142,-.020628,
.013128,-.019642,
.013928,-.0185,
.014518,-.017236,
.014878,-.015889,
.015,-.0145,
.015,.0145,
.014878,.015889,
.014518,.017236,
.013928,.0185,
.013128,.019642,
.012142,.020628,
.011,.021428,
.009736,.022018,
.008389,.022378,
.007,.0225,
-.007,.0225,
-.008389,.022378,
-.009736,.022018,
-.011,.021428,
-.012142,.020628,
-.013128,.019642,
-.013928,.0185,
-.014518,.017236,
-.014878,.015889,
-.015,.0145,
-.015,-.0145,
-.014878,-.015889,
-.014518,-.017236,
-.013928,-.0185,
-.013128,-.019642,
-.012142,-.020628,
-.011,-.021428,
-.009736,-.022018,
-.008389,-.022378,
-.007,-.0225,
.007,-.0225,
0.0*
%
%ADD13MACRO13*%
%AMMACRO11*
4,1,40,.007,-.011,
-.007,-.011,
-.007695,-.010939,
-.008368,-.010759,
-.009,-.010464,
-.009571,-.010064,
-.010064,-.009571,
-.010464,-.009,
-.010759,-.008368,
-.010939,-.007695,
-.011,-.007,
-.011,.007,
-.010939,.007695,
-.010759,.008368,
-.010464,.009,
-.010064,.009571,
-.009571,.010064,
-.009,.010464,
-.008368,.010759,
-.007695,.010939,
-.007,.011,
.007,.011,
.007695,.010939,
.008368,.010759,
.009,.010464,
.009571,.010064,
.010064,.009571,
.010464,.009,
.010759,.008368,
.010939,.007695,
.011,.007,
.011,-.007,
.010939,-.007695,
.010759,-.008368,
.010464,-.009,
.010064,-.009571,
.009571,-.010064,
.009,-.010464,
.008368,-.010759,
.007695,-.010939,
.007,-.011,
0.0*
%
%ADD11MACRO11*%
%AMMACRO12*
4,1,40,.007,-.011,
-.007,-.011,
-.007695,-.010939,
-.008368,-.010759,
-.009,-.010464,
-.009571,-.010064,
-.010064,-.009571,
-.010464,-.009,
-.010759,-.008368,
-.010939,-.007695,
-.011,-.007,
-.011,.007,
-.010939,.007695,
-.010759,.008368,
-.010464,.009,
-.010064,.009571,
-.009571,.010064,
-.009,.010464,
-.008368,.010759,
-.007695,.010939,
-.007,.011,
.007,.011,
.007695,.010939,
.008368,.010759,
.009,.010464,
.009571,.010064,
.010064,.009571,
.010464,.009,
.010759,.008368,
.010939,.007695,
.011,.007,
.011,-.007,
.010939,-.007695,
.010759,-.008368,
.010464,-.009,
.010064,-.009571,
.009571,-.010064,
.009,-.010464,
.008368,-.010759,
.007695,-.010939,
.007,-.011,
0.0*
%
%ADD12MACRO12*%
%ADD17R,.05X.065*%
%ADD21R,.024X.059*%
%ADD20R,.059X.079*%
%AMMACRO18*
4,1,40,.013,-.017,
-.013,-.017,
-.013695,-.016939,
-.014368,-.016759,
-.015,-.016464,
-.015571,-.016064,
-.016064,-.015571,
-.016464,-.015,
-.016759,-.014368,
-.016939,-.013695,
-.017,-.013,
-.017,.013,
-.016939,.013695,
-.016759,.014368,
-.016464,.015,
-.016064,.015571,
-.015571,.016064,
-.015,.016464,
-.014368,.016759,
-.013695,.016939,
-.013,.017,
.013,.017,
.013695,.016939,
.014368,.016759,
.015,.016464,
.015571,.016064,
.016064,.015571,
.016464,.015,
.016759,.014368,
.016939,.013695,
.017,.013,
.017,-.013,
.016939,-.013695,
.016759,-.014368,
.016464,-.015,
.016064,-.015571,
.015571,-.016064,
.015,-.016464,
.014368,-.016759,
.013695,-.016939,
.013,-.017,
0.0*
%
%ADD18MACRO18*%
%AMMACRO16*
4,1,40,-.017,-.013,
-.017,.013,
-.016939,.013695,
-.016759,.014368,
-.016464,.015,
-.016064,.015571,
-.015571,.016064,
-.015,.016464,
-.014368,.016759,
-.013695,.016939,
-.013,.017,
.013,.017,
.013695,.016939,
.014368,.016759,
.015,.016464,
.015571,.016064,
.016064,.015571,
.016464,.015,
.016759,.014368,
.016939,.013695,
.017,.013,
.017,-.013,
.016939,-.013695,
.016759,-.014368,
.016464,-.015,
.016064,-.015571,
.015571,-.016064,
.015,-.016464,
.014368,-.016759,
.013695,-.016939,
.013,-.017,
-.013,-.017,
-.013695,-.016939,
-.014368,-.016759,
-.015,-.016464,
-.015571,-.016064,
-.016064,-.015571,
-.016464,-.015,
-.016759,-.014368,
-.016939,-.013695,
-.017,-.013,
0.0*
%
%ADD16MACRO16*%
%ADD22C,.02*%
%ADD23C,.006*%
G75*
%LPD*%
G75*
G54D10*
X35851Y28624D03*
X48411Y920770D03*
X693601Y10159D03*
X751130Y826309D03*
X765026Y19107D03*
G54D20*
X167913Y40748D03*
X219095D03*
G54D11*
X74500Y11400D03*
X88400Y11800D03*
X115000Y10400D03*
X127800D03*
X253011Y12770D03*
X268522Y12786D03*
X418100Y13800D03*
X432200D03*
X558300Y13000D03*
X544800D03*
X651700Y12500D03*
X636600Y12300D03*
G54D21*
X175787Y34842D03*
X179724D03*
X183661D03*
X175787Y58858D03*
X179724D03*
X183661D03*
X187598Y34842D03*
X191535D03*
X195473D03*
X199410D03*
X203347D03*
X207284D03*
X211221D03*
X187598Y58858D03*
X191535D03*
X195473D03*
X199410D03*
X203347D03*
X207284D03*
X211221D03*
G54D12*
X77900Y11400D03*
X118400Y10400D03*
X91800Y11800D03*
X131200Y10400D03*
X256411Y12770D03*
X271922Y12786D03*
X421500Y13800D03*
X435600D03*
X561700Y13000D03*
X548200D03*
X655100Y12500D03*
X640000Y12300D03*
G54D22*
G01X-23515Y-108314D02*
X-55515D01*
G01X-23515Y-124314D02*
Y-204314D01*
G01D02*
X1177585D01*
G01X-27515Y-108314D02*
G02I-12000J0D01*
G01X-39515Y-124314D02*
Y-92314D01*
G01X-23515Y-124314D02*
X1177585D01*
G01X-23515Y-159814D02*
X1177585D01*
G01X-32665Y-108314D02*
G02I-6850J0D01*
G01X390085Y-124314D02*
Y-204314D01*
G01X527585Y-124314D02*
Y-204314D01*
G01X642585Y-124314D02*
Y-204314D01*
G01X810085Y-124314D02*
Y-204314D01*
G01X980085Y-124314D02*
Y-204314D01*
G01X1177585Y-124314D02*
Y-204314D01*
G01X1205585Y-108314D02*
G02I-12000J0D01*
G01X1200435D02*
G02I-6850J0D01*
G01X1209585D02*
X1177585D01*
G01X1193585Y-124314D02*
Y-92314D01*
G54D13*
X87800Y25050D03*
X83925Y17550D03*
X73700Y25050D03*
X77575Y17550D03*
X69825D03*
X126100Y23650D03*
X129975Y16150D03*
X122225D03*
X91675Y17550D03*
X112000Y23650D03*
X115875Y16150D03*
X108125D03*
X255107Y26004D03*
X258982Y18504D03*
X251232D03*
X269207Y26004D03*
X273082Y18504D03*
X265332D03*
X422775Y19550D03*
X415025D03*
X418900Y27050D03*
X436975Y19550D03*
X429225D03*
X433100Y27050D03*
X563175Y18750D03*
X555425D03*
X548975D03*
X541225D03*
X559300Y26250D03*
X545100D03*
X651700Y25750D03*
X655575Y18250D03*
X647825D03*
X637500Y25750D03*
X641375Y18250D03*
X633625D03*
G54D23*
G01X981Y-184981D02*
X1855Y-184106D01*
X2510Y-182648D01*
X2947Y-180605D01*
X2510Y-178856D01*
X1637Y-177689D01*
X108Y-176814D01*
X-5787D01*
Y-194314D01*
X1418D01*
X2947Y-193148D01*
X3820Y-191397D01*
X4257Y-189356D01*
X3820Y-187314D01*
X2510Y-185564D01*
X981Y-184981D01*
X-5787D01*
G01X13678Y-194314D02*
Y-182648D01*
G01Y-184981D02*
X14770Y-183814D01*
X15862Y-182939D01*
X17390Y-182648D01*
X18481Y-182939D01*
X19792Y-183814D01*
G01X29650Y-199564D02*
X30960Y-200147D01*
X32707Y-199564D01*
X33798Y-198398D01*
X34672Y-196939D01*
X35981Y-192273D01*
X38820Y-182648D01*
G01X31833D02*
X35981Y-192273D01*
G01X55228Y-184106D02*
X53700Y-182939D01*
X52390Y-182648D01*
X50643Y-183231D01*
X49333Y-184397D01*
X48460Y-186439D01*
X48241Y-188481D01*
X48460Y-190523D01*
X49333Y-192273D01*
X50643Y-193731D01*
X52390Y-194314D01*
X53918Y-193731D01*
X55228Y-192564D01*
G01X65960Y-186439D02*
X72947D01*
X72292Y-184397D01*
X71200Y-183231D01*
X69672Y-182648D01*
X68143Y-182939D01*
X66833Y-183814D01*
X65960Y-185856D01*
X65523Y-187606D01*
Y-189356D01*
X65960Y-191106D01*
X67052Y-192856D01*
X68362Y-194022D01*
X69890Y-194314D01*
X71418Y-193731D01*
X72947Y-191981D01*
G01X109038Y-178273D02*
X107728Y-177397D01*
X106200Y-176814D01*
X104453D01*
X102488Y-177689D01*
X100960Y-179147D01*
X99868Y-180898D01*
X98995Y-183814D01*
X98776Y-186439D01*
X99213Y-189064D01*
X99868Y-190814D01*
X101178Y-192564D01*
X102707Y-193731D01*
X104235Y-194314D01*
X105763D01*
X107292Y-193731D01*
X108602Y-192856D01*
X109694Y-191690D01*
G01X125665Y-194314D02*
Y-182648D01*
G01Y-184689D02*
X124792Y-183523D01*
X123481Y-182939D01*
X121953Y-182648D01*
X120425Y-183231D01*
X119115Y-184397D01*
X118241Y-186147D01*
X117805Y-188481D01*
X118241Y-190814D01*
X119115Y-192564D01*
X120425Y-193731D01*
X121953Y-194314D01*
X123481Y-194022D01*
X124792Y-193148D01*
X125665Y-191981D01*
G01X135523Y-194314D02*
Y-182648D01*
G01Y-185564D02*
X136397Y-184106D01*
X137707Y-182939D01*
X139453Y-182648D01*
X140981Y-182939D01*
X142292Y-184106D01*
X142947Y-186147D01*
Y-194314D01*
G01X152150Y-199564D02*
X153460Y-200147D01*
X155207Y-199564D01*
X156298Y-198398D01*
X157172Y-196939D01*
X158481Y-192273D01*
X161320Y-182648D01*
G01X154333D02*
X158481Y-192273D01*
G01X174235Y-194314D02*
X172925Y-194022D01*
X171615Y-192856D01*
X170741Y-190814D01*
X170305Y-188481D01*
X170741Y-186147D01*
X171615Y-184106D01*
X172925Y-182939D01*
X174235Y-182648D01*
X175545Y-182939D01*
X176855Y-184106D01*
X177728Y-186147D01*
X177947Y-188481D01*
X177728Y-190814D01*
X176855Y-192856D01*
X175545Y-194022D01*
X174235Y-194314D01*
G01X188023D02*
Y-182648D01*
G01Y-185564D02*
X188897Y-184106D01*
X190207Y-182939D01*
X191953Y-182648D01*
X193481Y-182939D01*
X194792Y-184106D01*
X195447Y-186147D01*
Y-194314D01*
G01X222368Y-176814D02*
Y-194314D01*
X231102D01*
G01X248602D02*
X239868D01*
Y-176814D01*
X248602D01*
G01X245108Y-185272D02*
X239868D01*
G01X256932Y-194314D02*
Y-176814D01*
X261298D01*
X263045Y-177689D01*
X264355Y-178856D01*
X265447Y-180605D01*
X266320Y-182648D01*
X266538Y-185564D01*
X266320Y-188481D01*
X265447Y-190523D01*
X264355Y-192273D01*
X263045Y-193439D01*
X261298Y-194314D01*
X256932D01*
G01X298481Y-184981D02*
X299355Y-184106D01*
X300010Y-182648D01*
X300447Y-180605D01*
X300010Y-178856D01*
X299137Y-177689D01*
X297608Y-176814D01*
X291713D01*
Y-194314D01*
X298918D01*
X300447Y-193148D01*
X301320Y-191397D01*
X301757Y-189356D01*
X301320Y-187314D01*
X300010Y-185564D01*
X298481Y-184981D01*
X291713D01*
G01X314235Y-194314D02*
X312925Y-194022D01*
X311615Y-192856D01*
X310741Y-190814D01*
X310305Y-188481D01*
X310741Y-186147D01*
X311615Y-184106D01*
X312925Y-182939D01*
X314235Y-182648D01*
X315545Y-182939D01*
X316855Y-184106D01*
X317728Y-186147D01*
X317947Y-188481D01*
X317728Y-190814D01*
X316855Y-192856D01*
X315545Y-194022D01*
X314235Y-194314D01*
G01X335665D02*
Y-182648D01*
G01Y-184689D02*
X334792Y-183523D01*
X333481Y-182939D01*
X331953Y-182648D01*
X330425Y-183231D01*
X329115Y-184397D01*
X328241Y-186147D01*
X327805Y-188481D01*
X328241Y-190814D01*
X329115Y-192564D01*
X330425Y-193731D01*
X331953Y-194314D01*
X333481Y-194022D01*
X334792Y-193148D01*
X335665Y-191981D01*
G01X346178Y-194314D02*
Y-182648D01*
G01Y-184981D02*
X347270Y-183814D01*
X348362Y-182939D01*
X349890Y-182648D01*
X350981Y-182939D01*
X352292Y-183814D01*
G01X370665Y-176814D02*
Y-194314D01*
G01Y-191690D02*
X369792Y-193148D01*
X368481Y-194022D01*
X366953Y-194314D01*
X365207Y-193731D01*
X363897Y-192273D01*
X363023Y-190523D01*
X362805Y-188481D01*
X363023Y-186439D01*
X363897Y-184689D01*
X365207Y-183231D01*
X366953Y-182648D01*
X368481Y-182939D01*
X369573Y-183523D01*
X370665Y-184689D01*
G01X142308Y-149314D02*
Y-131814D01*
X147985Y-146397D01*
X153662Y-131814D01*
Y-149314D01*
G01X165485D02*
X164175Y-149022D01*
X162865Y-147856D01*
X161991Y-145814D01*
X161555Y-143481D01*
X161991Y-141147D01*
X162865Y-139106D01*
X164175Y-137939D01*
X165485Y-137648D01*
X166795Y-137939D01*
X168105Y-139106D01*
X168978Y-141147D01*
X169197Y-143481D01*
X168978Y-145814D01*
X168105Y-147856D01*
X166795Y-149022D01*
X165485Y-149314D01*
G01X186915Y-131814D02*
Y-149314D01*
G01Y-146690D02*
X186042Y-148148D01*
X184731Y-149022D01*
X183203Y-149314D01*
X181457Y-148731D01*
X180147Y-147273D01*
X179273Y-145523D01*
X179055Y-143481D01*
X179273Y-141439D01*
X180147Y-139689D01*
X181457Y-138231D01*
X183203Y-137648D01*
X184731Y-137939D01*
X185823Y-138523D01*
X186915Y-139689D01*
G01X197210Y-141439D02*
X204197D01*
X203542Y-139397D01*
X202450Y-138231D01*
X200922Y-137648D01*
X199393Y-137939D01*
X198083Y-138814D01*
X197210Y-140856D01*
X196773Y-142606D01*
Y-144356D01*
X197210Y-146106D01*
X198302Y-147856D01*
X199612Y-149022D01*
X201140Y-149314D01*
X202668Y-148731D01*
X204197Y-146981D01*
G01X217985Y-149314D02*
Y-131814D01*
G01X423785Y-194314D02*
Y-176814D01*
X421165Y-180314D01*
G01Y-194314D02*
X426405D01*
G01X437137Y-187023D02*
X438665Y-184981D01*
X439975Y-183814D01*
X441722Y-183231D01*
X443250Y-183814D01*
X444342Y-184981D01*
X445215Y-186731D01*
X445433Y-188772D01*
X445215Y-190523D01*
X444342Y-192273D01*
X443031Y-193731D01*
X441503Y-194314D01*
X439757Y-193731D01*
X438228Y-191981D01*
X437355Y-189356D01*
X437137Y-186439D01*
X437573Y-182648D01*
X438228Y-180605D01*
X439320Y-178564D01*
X440848Y-177106D01*
X442377Y-176814D01*
X443905Y-177397D01*
X444997Y-178856D01*
G01X453982Y-190814D02*
X455291Y-192856D01*
X457038Y-194022D01*
X459003Y-194314D01*
X460750Y-194022D01*
X462497Y-192564D01*
X463588Y-190814D01*
X463807Y-189064D01*
X463370Y-187023D01*
X461842Y-185564D01*
X460313Y-184981D01*
X458348D01*
G01X460313D02*
X461623Y-184106D01*
X462715Y-182648D01*
X463152Y-180898D01*
X462715Y-179147D01*
X461623Y-177689D01*
X459658Y-176814D01*
X457693Y-177106D01*
X455728Y-178273D01*
G01X478905Y-194314D02*
Y-176814D01*
X470826Y-189356D01*
X481744D01*
G01X493348Y-194314D02*
X493785Y-190523D01*
X494440Y-187314D01*
X495313Y-184397D01*
X496405Y-181189D01*
X498152Y-176814D01*
X489418D01*
G01X410668Y-149314D02*
Y-131814D01*
X415908D01*
X417655Y-132689D01*
X418965Y-134731D01*
X419402Y-137064D01*
X418965Y-139397D01*
X417873Y-141147D01*
X415908Y-142023D01*
X410668D01*
G01X437338Y-133273D02*
X436028Y-132397D01*
X434500Y-131814D01*
X432753D01*
X430788Y-132689D01*
X429260Y-134147D01*
X428168Y-135898D01*
X427295Y-138814D01*
X427076Y-141439D01*
X427513Y-144064D01*
X428168Y-145814D01*
X429478Y-147564D01*
X431007Y-148731D01*
X432535Y-149314D01*
X434063D01*
X435592Y-148731D01*
X436902Y-147856D01*
X437994Y-146690D01*
G01X451781Y-139981D02*
X452655Y-139106D01*
X453310Y-137648D01*
X453747Y-135605D01*
X453310Y-133856D01*
X452437Y-132689D01*
X450908Y-131814D01*
X445013D01*
Y-149314D01*
X452218D01*
X453747Y-148148D01*
X454620Y-146397D01*
X455057Y-144356D01*
X454620Y-142314D01*
X453310Y-140564D01*
X451781Y-139981D01*
X445013D01*
G01X460985Y-155147D02*
X474085D01*
G01X480013Y-149314D02*
Y-131814D01*
X490057Y-149314D01*
Y-131814D01*
G01X502535Y-149314D02*
X500788Y-149022D01*
X499260Y-147856D01*
X497950Y-146106D01*
X497076Y-144064D01*
X496640Y-141731D01*
Y-139397D01*
X497076Y-137064D01*
X497950Y-135022D01*
X499260Y-133273D01*
X500788Y-132106D01*
X502535Y-131814D01*
X504281Y-132106D01*
X505810Y-133273D01*
X507120Y-135022D01*
X507994Y-137064D01*
X508430Y-139397D01*
Y-141731D01*
X507994Y-144064D01*
X507120Y-146106D01*
X505810Y-147856D01*
X504281Y-149022D01*
X502535Y-149314D01*
G01X553376Y-131814D02*
X558835Y-149314D01*
X564294Y-131814D01*
G01X580702Y-149314D02*
X571968D01*
Y-131814D01*
X580702D01*
G01X577208Y-140272D02*
X571968D01*
G01X589468Y-149314D02*
Y-131814D01*
X594927D01*
X596673Y-132689D01*
X597765Y-133856D01*
X598202Y-136189D01*
X597765Y-138523D01*
X596455Y-139981D01*
X594927Y-140856D01*
X589468D01*
G01X594927D02*
X598202Y-149314D01*
G01X611335Y-149897D02*
X610898Y-149606D01*
Y-149022D01*
X611335Y-148731D01*
X611772Y-149022D01*
Y-149606D01*
X611335Y-149897D01*
G01X571750Y-191981D02*
X573497Y-193439D01*
X575462Y-194314D01*
X577208D01*
X578955Y-193439D01*
X580265Y-191981D01*
X580920Y-189939D01*
X580483Y-187898D01*
X579392Y-186147D01*
X577427Y-184981D01*
X574807Y-184397D01*
X573278Y-183231D01*
X572623Y-181189D01*
X573060Y-179147D01*
X574152Y-177689D01*
X575680Y-176814D01*
X577208D01*
X578737Y-177397D01*
X580047Y-178856D01*
G01X598638Y-178273D02*
X597328Y-177397D01*
X595800Y-176814D01*
X594053D01*
X592088Y-177689D01*
X590560Y-179147D01*
X589468Y-180898D01*
X588595Y-183814D01*
X588376Y-186439D01*
X588813Y-189064D01*
X589468Y-190814D01*
X590778Y-192564D01*
X592307Y-193731D01*
X593835Y-194314D01*
X595363D01*
X596892Y-193731D01*
X598202Y-192856D01*
X599294Y-191690D01*
G01X750789Y-184981D02*
X749915Y-184106D01*
X749260Y-182648D01*
X748823Y-180605D01*
X749260Y-178856D01*
X750133Y-177689D01*
X751662Y-176814D01*
X757557D01*
Y-194314D01*
X750352D01*
X748823Y-193148D01*
X747950Y-191397D01*
X747513Y-189356D01*
X747950Y-187314D01*
X749260Y-185564D01*
X750789Y-184981D01*
X757557D01*
G01X739620Y-191981D02*
X737873Y-193439D01*
X735908Y-194314D01*
X734162D01*
X732415Y-193439D01*
X731105Y-191981D01*
X730450Y-189939D01*
X730887Y-187898D01*
X731978Y-186147D01*
X733943Y-184981D01*
X736563Y-184397D01*
X738092Y-183231D01*
X738747Y-181189D01*
X738310Y-179147D01*
X737218Y-177689D01*
X735690Y-176814D01*
X734162D01*
X732633Y-177397D01*
X731323Y-178856D01*
G01X723212Y-194314D02*
Y-176814D01*
X717535Y-191397D01*
X711858Y-176814D01*
Y-194314D01*
G01X704838D02*
Y-176814D01*
X700472D01*
X698725Y-177689D01*
X697415Y-178856D01*
X696323Y-180605D01*
X695450Y-182648D01*
X695232Y-185564D01*
X695450Y-188481D01*
X696323Y-190523D01*
X697415Y-192273D01*
X698725Y-193439D01*
X700472Y-194314D01*
X704838D01*
G01X686918Y-131814D02*
Y-149314D01*
X695652D01*
G01X712715D02*
Y-137648D01*
G01Y-139689D02*
X711842Y-138523D01*
X710531Y-137939D01*
X709003Y-137648D01*
X707475Y-138231D01*
X706165Y-139397D01*
X705291Y-141147D01*
X704855Y-143481D01*
X705291Y-145814D01*
X706165Y-147564D01*
X707475Y-148731D01*
X709003Y-149314D01*
X710531Y-149022D01*
X711842Y-148148D01*
X712715Y-146981D01*
G01X721700Y-154564D02*
X723010Y-155147D01*
X724757Y-154564D01*
X725848Y-153398D01*
X726722Y-151939D01*
X728031Y-147273D01*
X730870Y-137648D01*
G01X723883D02*
X728031Y-147273D01*
G01X740510Y-141439D02*
X747497D01*
X746842Y-139397D01*
X745750Y-138231D01*
X744222Y-137648D01*
X742693Y-137939D01*
X741383Y-138814D01*
X740510Y-140856D01*
X740073Y-142606D01*
Y-144356D01*
X740510Y-146106D01*
X741602Y-147856D01*
X742912Y-149022D01*
X744440Y-149314D01*
X745968Y-148731D01*
X747497Y-146981D01*
G01X758228Y-149314D02*
Y-137648D01*
G01Y-139981D02*
X759320Y-138814D01*
X760412Y-137939D01*
X761940Y-137648D01*
X763031Y-137939D01*
X764342Y-138814D01*
G01X851335Y-194314D02*
X849588Y-194022D01*
X848060Y-192856D01*
X846750Y-191106D01*
X845876Y-189064D01*
X845440Y-186731D01*
Y-184397D01*
X845876Y-182064D01*
X846750Y-180022D01*
X848060Y-178273D01*
X849588Y-177106D01*
X851335Y-176814D01*
X853081Y-177106D01*
X854610Y-178273D01*
X855920Y-180022D01*
X856794Y-182064D01*
X857230Y-184397D01*
Y-186731D01*
X856794Y-189064D01*
X855920Y-191106D01*
X854610Y-192856D01*
X853081Y-194022D01*
X851335Y-194314D01*
G01X853081Y-189647D02*
X855702Y-194314D01*
G01X864032Y-176814D02*
Y-189356D01*
X864905Y-191981D01*
X866652Y-193731D01*
X868835Y-194314D01*
X871018Y-193731D01*
X872765Y-191981D01*
X873638Y-189356D01*
Y-176814D01*
G01X883715D02*
X888955D01*
G01X886335D02*
Y-194314D01*
G01X883715D02*
X888955D01*
G01X898813D02*
Y-176814D01*
X908857Y-194314D01*
Y-176814D01*
G01X926138Y-178273D02*
X924828Y-177397D01*
X923300Y-176814D01*
X921553D01*
X919588Y-177689D01*
X918060Y-179147D01*
X916968Y-180898D01*
X916095Y-183814D01*
X915876Y-186439D01*
X916313Y-189064D01*
X916968Y-190814D01*
X918278Y-192564D01*
X919807Y-193731D01*
X921335Y-194314D01*
X922863D01*
X924392Y-193731D01*
X925702Y-192856D01*
X926794Y-191690D01*
G01X938835Y-194314D02*
Y-186439D01*
X934468Y-176814D01*
G01X943202D02*
X938835Y-186439D01*
G01X829032Y-149314D02*
Y-131814D01*
X833398D01*
X835145Y-132689D01*
X836455Y-133856D01*
X837547Y-135605D01*
X838420Y-137648D01*
X838638Y-140564D01*
X838420Y-143481D01*
X837547Y-145523D01*
X836455Y-147273D01*
X835145Y-148439D01*
X833398Y-149314D01*
X829032D01*
G01X848060Y-141439D02*
X855047D01*
X854392Y-139397D01*
X853300Y-138231D01*
X851772Y-137648D01*
X850243Y-137939D01*
X848933Y-138814D01*
X848060Y-140856D01*
X847623Y-142606D01*
Y-144356D01*
X848060Y-146106D01*
X849152Y-147856D01*
X850462Y-149022D01*
X851990Y-149314D01*
X853518Y-148731D01*
X855047Y-146981D01*
G01X865560Y-147273D02*
X866652Y-148439D01*
X868180Y-149314D01*
X869490D01*
X870800Y-148731D01*
X871673Y-147856D01*
X872110Y-146690D01*
X871892Y-144939D01*
X871018Y-144064D01*
X867088Y-142314D01*
X866215Y-140272D01*
X866652Y-138814D01*
X867525Y-137939D01*
X868835Y-137648D01*
X870145Y-137939D01*
X871455Y-138814D01*
G01X886335Y-137648D02*
Y-149314D01*
G01Y-132981D02*
X885898Y-132689D01*
Y-132106D01*
X886335Y-131814D01*
X886772Y-132106D01*
Y-132689D01*
X886335Y-132981D01*
G01X900778Y-153689D02*
X902307Y-154856D01*
X904053Y-155147D01*
X905581Y-154856D01*
X906892Y-153398D01*
X907765Y-151356D01*
Y-137648D01*
G01Y-139981D02*
X906892Y-138814D01*
X905581Y-137939D01*
X904053Y-137648D01*
X902307Y-138231D01*
X901215Y-139397D01*
X900341Y-141439D01*
X899905Y-143481D01*
X900123Y-145231D01*
X900997Y-147273D01*
X902307Y-148731D01*
X904053Y-149314D01*
X905363Y-149022D01*
X906892Y-147856D01*
X907765Y-146690D01*
G01X917623Y-149314D02*
Y-137648D01*
G01Y-140564D02*
X918497Y-139106D01*
X919807Y-137939D01*
X921553Y-137648D01*
X923081Y-137939D01*
X924392Y-139106D01*
X925047Y-141147D01*
Y-149314D01*
G01X935560Y-141439D02*
X942547D01*
X941892Y-139397D01*
X940800Y-138231D01*
X939272Y-137648D01*
X937743Y-137939D01*
X936433Y-138814D01*
X935560Y-140856D01*
X935123Y-142606D01*
Y-144356D01*
X935560Y-146106D01*
X936652Y-147856D01*
X937962Y-149022D01*
X939490Y-149314D01*
X941018Y-148731D01*
X942547Y-146981D01*
G01X953278Y-149314D02*
Y-137648D01*
G01Y-139981D02*
X954370Y-138814D01*
X955462Y-137939D01*
X956990Y-137648D01*
X958081Y-137939D01*
X959392Y-138814D01*
G01X1000035Y-176814D02*
X998288Y-177397D01*
X996978Y-178856D01*
X996105Y-180605D01*
X995450Y-182939D01*
X995232Y-185564D01*
X995450Y-188189D01*
X996105Y-190523D01*
X996978Y-192273D01*
X998288Y-193731D01*
X1000035Y-194314D01*
X1001781Y-193731D01*
X1003092Y-192273D01*
X1003965Y-190523D01*
X1004620Y-188189D01*
X1004838Y-185564D01*
X1004620Y-182939D01*
X1003965Y-180605D01*
X1003092Y-178856D01*
X1001781Y-177397D01*
X1000035Y-176814D01*
G01X1012732Y-190814D02*
X1014041Y-192856D01*
X1015788Y-194022D01*
X1017753Y-194314D01*
X1019500Y-194022D01*
X1021247Y-192564D01*
X1022338Y-190814D01*
X1022557Y-189064D01*
X1022120Y-187023D01*
X1020592Y-185564D01*
X1019063Y-184981D01*
X1017098D01*
G01X1019063D02*
X1020373Y-184106D01*
X1021465Y-182648D01*
X1021902Y-180898D01*
X1021465Y-179147D01*
X1020373Y-177689D01*
X1018408Y-176814D01*
X1016443Y-177106D01*
X1014478Y-178273D01*
G01X1031105Y-194897D02*
X1038965Y-176814D01*
G01X1052535Y-194314D02*
Y-176814D01*
X1049915Y-180314D01*
G01Y-194314D02*
X1055155D01*
G01X1065232Y-190814D02*
X1066541Y-192856D01*
X1068288Y-194022D01*
X1070253Y-194314D01*
X1072000Y-194022D01*
X1073747Y-192564D01*
X1074838Y-190814D01*
X1075057Y-189064D01*
X1074620Y-187023D01*
X1073092Y-185564D01*
X1071563Y-184981D01*
X1069598D01*
G01X1071563D02*
X1072873Y-184106D01*
X1073965Y-182648D01*
X1074402Y-180898D01*
X1073965Y-179147D01*
X1072873Y-177689D01*
X1070908Y-176814D01*
X1068943Y-177106D01*
X1066978Y-178273D01*
G01X1083605Y-194897D02*
X1091465Y-176814D01*
G01X1100887Y-179731D02*
X1102197Y-177981D01*
X1103725Y-177106D01*
X1105472Y-176814D01*
X1107655Y-177397D01*
X1109183Y-178856D01*
X1109620Y-180605D01*
X1109402Y-182356D01*
X1108528Y-183814D01*
X1104162Y-186731D01*
X1102197Y-188772D01*
X1100887Y-191690D01*
X1100450Y-194314D01*
X1109620D01*
G01X1122535Y-176814D02*
X1120788Y-177397D01*
X1119478Y-178856D01*
X1118605Y-180605D01*
X1117950Y-182939D01*
X1117732Y-185564D01*
X1117950Y-188189D01*
X1118605Y-190523D01*
X1119478Y-192273D01*
X1120788Y-193731D01*
X1122535Y-194314D01*
X1124281Y-193731D01*
X1125592Y-192273D01*
X1126465Y-190523D01*
X1127120Y-188189D01*
X1127338Y-185564D01*
X1127120Y-182939D01*
X1126465Y-180605D01*
X1125592Y-178856D01*
X1124281Y-177397D01*
X1122535Y-176814D01*
G01X1140035Y-194314D02*
Y-176814D01*
X1137415Y-180314D01*
G01Y-194314D02*
X1142655D01*
G01X1157098D02*
X1157535Y-190523D01*
X1158190Y-187314D01*
X1159063Y-184397D01*
X1160155Y-181189D01*
X1161902Y-176814D01*
X1153168D01*
G01X1047732Y-149314D02*
Y-131814D01*
X1052098D01*
X1053845Y-132689D01*
X1055155Y-133856D01*
X1056247Y-135605D01*
X1057120Y-137648D01*
X1057338Y-140564D01*
X1057120Y-143481D01*
X1056247Y-145523D01*
X1055155Y-147273D01*
X1053845Y-148439D01*
X1052098Y-149314D01*
X1047732D01*
G01X1073965D02*
Y-137648D01*
G01Y-139689D02*
X1073092Y-138523D01*
X1071781Y-137939D01*
X1070253Y-137648D01*
X1068725Y-138231D01*
X1067415Y-139397D01*
X1066541Y-141147D01*
X1066105Y-143481D01*
X1066541Y-145814D01*
X1067415Y-147564D01*
X1068725Y-148731D01*
X1070253Y-149314D01*
X1071781Y-149022D01*
X1073092Y-148148D01*
X1073965Y-146981D01*
G01X1087535Y-131814D02*
Y-149314D01*
G01X1084478Y-137648D02*
X1090592D01*
G01X1101760Y-141439D02*
X1108747D01*
X1108092Y-139397D01*
X1107000Y-138231D01*
X1105472Y-137648D01*
X1103943Y-137939D01*
X1102633Y-138814D01*
X1101760Y-140856D01*
X1101323Y-142606D01*
Y-144356D01*
X1101760Y-146106D01*
X1102852Y-147856D01*
X1104162Y-149022D01*
X1105690Y-149314D01*
X1107218Y-148731D01*
X1108747Y-146981D01*
G01X21279Y19685D02*
G03X11201I-5039J0D01*
G01D02*
G03X21279I5039J0D01*
G01X3937Y-3937D02*
X724409D01*
G01X0Y0D02*
G03X3937Y-3937I3937J0D01*
G01X0Y35433D02*
Y0D01*
G01Y51181D02*
G03X3937Y47244I3937J0D01*
G01X0Y51181D02*
Y118898D01*
G01X4724Y47244D02*
X3937D01*
G01X29921Y63780D02*
Y47244D01*
G01X41732Y75591D02*
G03X29921Y63780I0J-11811D01*
G01X4724Y39370D02*
G03Y47244I0J3937D01*
G01X29921D02*
G03Y39370I0J-3937D01*
G01X3937D02*
G03X0Y35433I0J-3937D01*
G01X33858Y39370D02*
X3937D01*
G01X33858D02*
G03X37795Y43307I0J3937D01*
G01Y63780D02*
Y43307D01*
G01X41732Y67717D02*
G03X37795Y63780I0J-3937D01*
G01X65354Y67717D02*
X41732D01*
G01X3937Y122835D02*
G03X0Y118898I0J-3937D01*
G01X60828Y75591D02*
X41732D01*
G01X20531Y99213D02*
G03I-4291J0D01*
G01X29921Y122835D02*
X60828D01*
G01X21279Y154331D02*
G03X11201I-5039J0D01*
G01D02*
G03X21279I5039J0D01*
G01X3937Y130709D02*
X724409D01*
G01X0Y134646D02*
G03X3937Y130709I3937J0D01*
G01X0Y170079D02*
Y134646D01*
G01X4724Y122835D02*
G03Y130709I0J3937D01*
G01X29921D02*
G03Y122835I0J-3937D01*
G01X4724D02*
X3937D01*
G01X0Y185827D02*
G03X3937Y181890I3937J0D01*
G01X0Y185827D02*
Y253544D01*
G01X4724Y181890D02*
X3937D01*
G01X29921Y198426D02*
Y181890D01*
G01X41732Y210237D02*
G03X29921Y198426I0J-11811D01*
G01X60828Y210237D02*
X41732D01*
G01X4724Y174016D02*
G03Y181890I0J3937D01*
G01X29921D02*
G03Y174016I0J-3937D01*
G01X3937D02*
G03X0Y170079I0J-3937D01*
G01X33858Y174016D02*
X3937D01*
G01X33858D02*
G03X37795Y177953I0J3937D01*
G01Y198426D02*
Y177953D01*
G01X41732Y202363D02*
G03X37795Y198426I0J-3937D01*
G01X65354Y202363D02*
X41732D01*
G01X29921Y257481D02*
X60828D01*
G01X3937D02*
G03X0Y253544I0J-3937D01*
G01X4724Y257481D02*
G03Y265355I0J3937D01*
G01X29921D02*
G03Y257481I0J-3937D01*
G01X4724D02*
X3937D01*
G01X20531Y233859D02*
G03I-4291J0D01*
G01X4724Y308662D02*
G03Y316536I0J3937D01*
G01X29921D02*
G03Y308662I0J-3937D01*
G01X21279Y288977D02*
G03X11201I-5039J0D01*
G01D02*
G03X21279I5039J0D01*
G01X3937Y265355D02*
X724409D01*
G01X0Y269292D02*
G03X3937Y265355I3937J0D01*
G01X0Y304725D02*
Y269292D01*
G01X3937Y308662D02*
G03X0Y304725I0J-3937D01*
G01X33858Y308662D02*
X3937D01*
G01X33858D02*
G03X37795Y312599I0J3937D01*
G01X0Y320473D02*
G03X3937Y316536I3937J0D01*
G01X0Y320473D02*
Y388190D01*
G01X4724Y316536D02*
X3937D01*
G01X29921Y333072D02*
Y316536D01*
G01X41732Y344883D02*
G03X29921Y333072I0J-11811D01*
G01X60828Y344883D02*
X41732D01*
G01X37795Y333072D02*
Y312599D01*
G01X41732Y337009D02*
G03X37795Y333072I0J-3937D01*
G01X65354Y337009D02*
X41732D01*
G01X29921Y392127D02*
X60828D01*
G01X3937D02*
G03X0Y388190I0J-3937D01*
G01X4724Y392127D02*
G03Y400001I0J3937D01*
G01X29921D02*
G03Y392127I0J-3937D01*
G01X4724D02*
X3937D01*
G01X20531Y368505D02*
G03I-4291J0D01*
G01X3937Y400001D02*
X724409D01*
G01X0Y403938D02*
G03X3937Y400001I3937J0D01*
G01X0Y439371D02*
Y403938D01*
G01Y455119D02*
G03X3937Y451182I3937J0D01*
G01X4724D02*
X3937D01*
G01X29921Y467718D02*
Y451182D01*
G01X4724Y443308D02*
G03Y451182I0J3937D01*
G01X29921D02*
G03Y443308I0J-3937D01*
G01X21279Y423623D02*
G03X11201I-5039J0D01*
G01D02*
G03X21279I5039J0D01*
G01X3937Y443308D02*
G03X0Y439371I0J-3937D01*
G01X33858Y443308D02*
X3937D01*
G01X33858D02*
G03X37795Y447245I0J3937D01*
G01Y467718D02*
Y447245D01*
G01X0Y455119D02*
Y522836D01*
G01X41732Y479529D02*
G03X29921Y467718I0J-11811D01*
G01X60828Y479529D02*
X41732D01*
G01X20531Y503151D02*
G03I-4291J0D01*
G01X41732Y471655D02*
G03X37795Y467718I0J-3937D01*
G01X65354Y471655D02*
X41732D01*
G01X29921Y526773D02*
X60828D01*
G01X3937D02*
G03X0Y522836I0J-3937D01*
G01X4724Y526773D02*
G03Y534647I0J3937D01*
G01X29921D02*
G03Y526773I0J-3937D01*
G01X4724D02*
X3937D01*
G01Y534647D02*
X724409D01*
G01X0Y538584D02*
G03X3937Y534647I3937J0D01*
G01X0Y574017D02*
Y538584D01*
G01Y589765D02*
G03X3937Y585828I3937J0D01*
G01X0Y589765D02*
Y657482D01*
G01X4724Y585828D02*
X3937D01*
G01X29921Y602364D02*
Y585828D01*
G01X4724Y577954D02*
G03Y585828I0J3937D01*
G01X29921D02*
G03Y577954I0J-3937D01*
G01X21279Y558269D02*
G03X11201I-5039J0D01*
G01D02*
G03X21279I5039J0D01*
G01X3937Y577954D02*
G03X0Y574017I0J-3937D01*
G01X33858Y577954D02*
X3937D01*
G01X33858D02*
G03X37795Y581891I0J3937D01*
G01Y602364D02*
Y581891D01*
G01X41732Y614175D02*
G03X29921Y602364I0J-11811D01*
G01X60828Y614175D02*
X41732D01*
G01X20531Y637797D02*
G03I-4291J0D01*
G01X41732Y606301D02*
G03X37795Y602364I0J-3937D01*
G01X65354Y606301D02*
X41732D01*
G01X29921Y661419D02*
X60828D01*
G01X3937D02*
G03X0Y657482I0J-3937D01*
G01X4724Y661419D02*
G03Y669293I0J3937D01*
G01X29921D02*
G03Y661419I0J-3937D01*
G01X4724D02*
X3937D01*
G01X11201Y692915D02*
G03X21279I5039J0D01*
G01X3937Y669293D02*
X724409D01*
G01X0Y673230D02*
G03X3937Y669293I3937J0D01*
G01X0Y708663D02*
Y673230D01*
G01Y724411D02*
G03X3937Y720474I3937J0D01*
G01X0Y724411D02*
Y792128D01*
G01X4724Y720474D02*
X3937D01*
G01X29921Y737010D02*
Y720474D01*
G01X41732Y748821D02*
G03X29921Y737010I0J-11811D01*
G01X4724Y712600D02*
G03Y720474I0J3937D01*
G01X29921D02*
G03Y712600I0J-3937D01*
G01X21279Y692915D02*
G03X11201I-5039J0D01*
G01X3937Y712600D02*
G03X0Y708663I0J-3937D01*
G01X33858Y712600D02*
X3937D01*
G01X33858D02*
G03X37795Y716537I0J3937D01*
G01Y737010D02*
Y716537D01*
G01X41732Y740947D02*
G03X37795Y737010I0J-3937D01*
G01X60828Y748821D02*
X41732D01*
G01X20531Y772443D02*
G03I-4291J0D01*
G01X65354Y740947D02*
X41732D01*
G01X29921Y796065D02*
X60828D01*
G01X3937D02*
G03X0Y792128I0J-3937D01*
G01X4724Y796065D02*
G03Y803939I0J3937D01*
G01X29921D02*
G03Y796065I0J-3937D01*
G01X4724D02*
X3937D01*
G01X21279Y827561D02*
G03X11201I-5039J0D01*
G01D02*
G03X21279I5039J0D01*
G01X3937Y803939D02*
X724409D01*
G01X0Y807876D02*
G03X3937Y803939I3937J0D01*
G01X0Y843309D02*
Y807876D01*
G01Y859057D02*
G03X3937Y855120I3937J0D01*
G01X0Y859057D02*
Y922837D01*
G01X4724Y855120D02*
X3937D01*
G01X29921Y871656D02*
Y855120D01*
G01X41732Y883467D02*
G03X29921Y871656I0J-11811D01*
G01X4724Y847246D02*
G03Y855120I0J3937D01*
G01X29921D02*
G03Y847246I0J-3937D01*
G01X3937D02*
G03X0Y843309I0J-3937D01*
G01X33858Y847246D02*
X3937D01*
G01X33858D02*
G03X37795Y851183I0J3937D01*
G01Y871656D02*
Y851183D01*
G01X41732Y875593D02*
G03X37795Y871656I0J-3937D01*
G01X65354Y875593D02*
X41732D01*
G01X7874Y930711D02*
G03X0Y922837I0J-7874D01*
G01X60828Y883467D02*
X41732D01*
G01X20531Y907089D02*
G03I-4291J0D01*
G01X60828Y930711D02*
X7874D01*
G01X53445Y19685D02*
G03X42028I-5709J0D01*
G01D02*
G03X53445I5709J0D01*
G01X69291Y63780D02*
G03X65354Y67717I-3937J0D01*
G01X69291Y43307D02*
Y63780D01*
G01Y43307D02*
G03X73228Y39370I3937J0D01*
G01X156102D02*
X73228D01*
G01X64765Y118898D02*
G03X60828Y122835I-3937J0D01*
G01Y75591D02*
G03X64765Y79528I0J3937D01*
G01Y113780D02*
Y118898D01*
G01X72639Y88583D02*
G03X64765I-3937J0D01*
G01Y113780D02*
G03X72639I3937J0D01*
G01X64765Y88583D02*
Y79528D01*
G01X83879Y99213D02*
G03X93879I5000J0D01*
G01D02*
G03X83879I-5000J0D01*
G01X76576Y122835D02*
G03X72639Y118898I0J-3937D01*
G01X76576Y79528D02*
X106694D01*
G01X72639Y83465D02*
G03X76576Y79528I3937J0D01*
G01X72639Y118898D02*
Y83465D01*
G01X53445Y154331D02*
G03X42028I-5709J0D01*
G01D02*
G03X53445I5709J0D01*
G01X797048Y122835D02*
X76576D01*
G01X60828Y210237D02*
G03X64765Y214174I0J3937D01*
G01Y223229D02*
Y214174D01*
G01X76576D02*
X106694D01*
G01X72639Y218111D02*
G03X76576Y214174I3937J0D01*
G01X69291Y198426D02*
G03X65354Y202363I-3937J0D01*
G01X69291Y177953D02*
Y198426D01*
G01Y177953D02*
G03X73228Y174016I3937J0D01*
G01X156102D02*
X73228D01*
G01X64765Y253544D02*
G03X60828Y257481I-3937J0D01*
G01X64765Y248426D02*
Y253544D01*
G01X72639Y223229D02*
G03X64765I-3937J0D01*
G01Y248426D02*
G03X72639I3937J0D01*
G01X83879Y233859D02*
G03X93879I5000J0D01*
G01D02*
G03X83879I-5000J0D01*
G01X76576Y257481D02*
G03X72639Y253544I0J-3937D01*
G01X797048Y257481D02*
X76576D01*
G01X72639Y253544D02*
Y218111D01*
G01X53445Y288977D02*
G03X42028I-5709J0D01*
G01D02*
G03X53445I5709J0D01*
G01X69291Y312599D02*
G03X73228Y308662I3937J0D01*
G01X156102D02*
X73228D01*
G01X60828Y344883D02*
G03X64765Y348820I0J3937D01*
G01X72639Y357875D02*
G03X64765I-3937J0D01*
G01D02*
Y348820D01*
G01X76576D02*
X106694D01*
G01X72639Y352757D02*
G03X76576Y348820I3937J0D01*
G01X72639Y388190D02*
Y352757D01*
G01X69291Y333072D02*
G03X65354Y337009I-3937J0D01*
G01X69291Y312599D02*
Y333072D01*
G01X64765Y388190D02*
G03X60828Y392127I-3937J0D01*
G01X64765Y383072D02*
Y388190D01*
G01Y383072D02*
G03X72639I3937J0D01*
G01X83879Y368505D02*
G03X93879I5000J0D01*
G01D02*
G03X83879I-5000J0D01*
G01X76576Y392127D02*
G03X72639Y388190I0J-3937D01*
G01X797048Y392127D02*
X76576D01*
G01X53445Y423623D02*
G03X42028I-5709J0D01*
G01D02*
G03X53445I5709J0D01*
G01X69291Y447245D02*
Y467718D01*
G01Y447245D02*
G03X73228Y443308I3937J0D01*
G01X156102D02*
X73228D01*
G01X60828Y479529D02*
G03X64765Y483466I0J3937D01*
G01X72639Y492521D02*
G03X64765I-3937J0D01*
G01D02*
Y483466D01*
G01X83879Y503151D02*
G03X93879I5000J0D01*
G01X76576Y483466D02*
X106694D01*
G01X72639Y487403D02*
G03X76576Y483466I3937J0D01*
G01X72639Y522836D02*
Y487403D01*
G01X69291Y467718D02*
G03X65354Y471655I-3937J0D01*
G01X64765Y522836D02*
G03X60828Y526773I-3937J0D01*
G01X64765Y517718D02*
Y522836D01*
G01Y517718D02*
G03X72639I3937J0D01*
G01X93879Y503151D02*
G03X83879I-5000J0D01*
G01X76576Y526773D02*
G03X72639Y522836I0J-3937D01*
G01X797048Y526773D02*
X76576D01*
G01X53445Y558269D02*
G03X42028I-5709J0D01*
G01D02*
G03X53445I5709J0D01*
G01X69291Y581891D02*
Y602364D01*
G01Y581891D02*
G03X73228Y577954I3937J0D01*
G01X156102D02*
X73228D01*
G01X60828Y614175D02*
G03X64765Y618112I0J3937D01*
G01X72639Y627167D02*
G03X64765I-3937J0D01*
G01D02*
Y618112D01*
G01X83879Y637797D02*
G03X93879I5000J0D01*
G01D02*
G03X83879I-5000J0D01*
G01X76576Y618112D02*
X106694D01*
G01X72639Y622049D02*
G03X76576Y618112I3937J0D01*
G01X72639Y657482D02*
Y622049D01*
G01X69291Y602364D02*
G03X65354Y606301I-3937J0D01*
G01X64765Y657482D02*
G03X60828Y661419I-3937J0D01*
G01X64765Y652364D02*
Y657482D01*
G01Y652364D02*
G03X72639I3937J0D01*
G01X42028Y692915D02*
G03X53445I5709J0D01*
G01X76576Y661419D02*
G03X72639Y657482I0J-3937D01*
G01X797048Y661419D02*
X76576D01*
G01X53445Y692915D02*
G03X42028I-5709J0D01*
G01X69291Y737010D02*
G03X65354Y740947I-3937J0D01*
G01X69291Y716537D02*
Y737010D01*
G01Y716538D02*
G03X73228Y712601I3937J0D01*
G01X156102Y712600D02*
X73228D01*
G01X60828Y748821D02*
G03X64765Y752758I0J3937D01*
G01Y787010D02*
Y792128D01*
G01X72639Y761813D02*
G03X64765I-3937J0D01*
G01Y787010D02*
G03X72639I3937J0D01*
G01X64765Y761813D02*
Y752758D01*
G01X83879Y772443D02*
G03X93879I5000J0D01*
G01D02*
G03X83879I-5000J0D01*
G01X76576Y752758D02*
X106694D01*
G01X72639Y756695D02*
G03X76576Y752758I3937J0D01*
G01X72639Y792128D02*
Y756695D01*
G01X64765Y792128D02*
G03X60828Y796065I-3937J0D01*
G01X53445Y827561D02*
G03X42028I-5709J0D01*
G01D02*
G03X53445I5709J0D01*
G01X76576Y796065D02*
G03X72639Y792128I0J-3937D01*
G01X797048Y796065D02*
X76576D01*
G01X69291Y871656D02*
G03X65354Y875593I-3937J0D01*
G01X69291Y851183D02*
Y871656D01*
G01Y851184D02*
G03X73228Y847247I3937J0D01*
G01X156102Y847246D02*
X73228D01*
G01X60828Y883467D02*
G03X64765Y887404I0J3937D01*
G01Y926774D02*
G03X60828Y930711I-3937J0D01*
G01X64765Y921656D02*
Y926774D01*
G01X72639Y896459D02*
G03X64765I-3937J0D01*
G01Y921656D02*
G03X72639I3937J0D01*
G01X64765Y896459D02*
Y887404D01*
G01X83879Y907089D02*
G03X93879I5000J0D01*
G01D02*
G03X83879I-5000J0D01*
G01X76576Y930711D02*
G03X72639Y926774I0J-3937D01*
G01X76576Y887404D02*
X106694D01*
G01X72639Y891341D02*
G03X76576Y887404I3937J0D01*
G01X72639Y926774D02*
Y891341D01*
G01X797048Y930711D02*
X76576D01*
G01X114568Y51181D02*
X138190D01*
G01X110631Y55118D02*
G03X114568Y51181I3937J0D01*
G01X110631Y75591D02*
Y55118D01*
G01X114666Y99213D02*
G03X126083I5708J0D01*
G01D02*
G03X114666I-5709J0D01*
G01X110631Y75591D02*
G03X106694Y79528I-3937J0D01*
G01X114568Y185827D02*
X138190D01*
G01X110631Y189764D02*
G03X114568Y185827I3937J0D01*
G01X110631Y210237D02*
Y189764D01*
G01Y210237D02*
G03X106694Y214174I-3937J0D01*
G01X114666Y233859D02*
G03X126083I5708J0D01*
G01D02*
G03X114666I-5709J0D01*
G01X114568Y320473D02*
X138190D01*
G01X110631Y324410D02*
G03X114568Y320473I3937J0D01*
G01X110631Y344883D02*
Y324410D01*
G01Y344883D02*
G03X106694Y348820I-3937J0D01*
G01X114666Y368505D02*
G03X126083I5708J0D01*
G01D02*
G03X114666I-5709J0D01*
G01Y503151D02*
G03X126083I5708J0D01*
G01X114568Y455119D02*
X138190D01*
G01X110631Y459056D02*
G03X114568Y455119I3937J0D01*
G01X110631Y479529D02*
Y459056D01*
G01Y479529D02*
G03X106694Y483466I-3937J0D01*
G01X126083Y503151D02*
G03X114666I-5709J0D01*
G01X114568Y589765D02*
X138190D01*
G01X110631Y593702D02*
G03X114568Y589765I3937J0D01*
G01X110631Y614175D02*
Y593702D01*
G01X114666Y637797D02*
G03X126083I5708J0D01*
G01D02*
G03X114666I-5709J0D01*
G01X110631Y614175D02*
G03X106694Y618112I-3937J0D01*
G01X114568Y724411D02*
X138190D01*
G01X110631Y728348D02*
G03X114568Y724411I3937J0D01*
G01X110631Y748821D02*
Y728348D01*
G01X114666Y772443D02*
G03X126083I5708J0D01*
G01D02*
G03X114666I-5709J0D01*
G01X110631Y748821D02*
G03X106694Y752758I-3937J0D01*
G01X114568Y859057D02*
X138190D01*
G01X110631Y862994D02*
G03X114568Y859057I3937J0D01*
G01X110631Y883467D02*
Y862994D01*
G01X114666Y907089D02*
G03X126083I5708J0D01*
G01D02*
G03X114666I-5709J0D01*
G01X110631Y883467D02*
G03X106694Y887404I-3937J0D01*
G01X142127Y55118D02*
Y75591D01*
G01X138190Y51181D02*
G03X142127Y55118I0J3937D01*
G01X180905Y71654D02*
G03Y79528I0J3937D01*
G01X156102Y39370D02*
G03X160039Y43307I0J3937D01*
G01Y67717D02*
Y43307D01*
G01X163976Y71654D02*
G03X160039Y67717I0J-3937D01*
G01X223031Y71654D02*
X163976D01*
G01X146064Y79528D02*
X230906D01*
G01X146064D02*
G03X142127Y75591I0J-3937D01*
G01X146064Y214174D02*
X230906D01*
G01X146064D02*
G03X142127Y210237I0J-3937D01*
G01Y189764D02*
Y210237D01*
G01X138190Y185827D02*
G03X142127Y189764I0J3937D01*
G01X180905Y206300D02*
G03Y214174I0J3937D01*
G01X156102Y174016D02*
G03X160039Y177953I0J3937D01*
G01Y202363D02*
Y177953D01*
G01X163976Y206300D02*
G03X160039Y202363I0J-3937D01*
G01X223031Y206300D02*
X163976D01*
G01X156102Y308662D02*
G03X160039Y312599I0J3937D01*
G01X146064Y348820D02*
X230906D01*
G01X146064D02*
G03X142127Y344883I0J-3937D01*
G01Y324410D02*
Y344883D01*
G01X138190Y320473D02*
G03X142127Y324410I0J3937D01*
G01X180905Y340946D02*
G03Y348820I0J3937D01*
G01X160039Y337009D02*
Y312599D01*
G01X163976Y340946D02*
G03X160039Y337009I0J-3937D01*
G01X223031Y340946D02*
X163976D01*
G01X156102Y443308D02*
G03X160039Y447245I0J3937D01*
G01Y471655D02*
Y447245D01*
G01X146064Y483466D02*
X230906D01*
G01X146064D02*
G03X142127Y479529I0J-3937D01*
G01Y459056D02*
Y479529D01*
G01X138190Y455120D02*
G03X142127Y459057I0J3937D01*
G01X180905Y475592D02*
G03Y483466I0J3937D01*
G01X163976Y475592D02*
G03X160039Y471655I0J-3937D01*
G01X223031Y475592D02*
X163976D01*
G01X142127Y593702D02*
Y614175D01*
G01X138190Y589766D02*
G03X142127Y593703I0J3937D01*
G01X156102Y577954D02*
G03X160039Y581891I0J3937D01*
G01Y606301D02*
Y581891D01*
G01X146064Y618112D02*
X230906D01*
G01X146064D02*
G03X142127Y614175I0J-3937D01*
G01X180905Y610238D02*
G03Y618112I0J3937D01*
G01X163976Y610238D02*
G03X160039Y606301I0J-3937D01*
G01X223031Y610238D02*
X163976D01*
G01X142127Y728348D02*
Y748821D01*
G01X138190Y724412D02*
G03X142127Y728349I0J3937D01*
G01X156102Y712600D02*
G03X160039Y716537I0J3937D01*
G01Y740947D02*
Y716537D01*
G01X146064Y752758D02*
X230906D01*
G01X146064D02*
G03X142127Y748821I0J-3937D01*
G01X180905Y744884D02*
G03Y752758I0J3937D01*
G01X163976Y744884D02*
G03X160039Y740947I0J-3937D01*
G01X223031Y744884D02*
X163976D01*
G01X142127Y862994D02*
Y883467D01*
G01X138190Y859058D02*
G03X142127Y862995I0J3937D01*
G01X180905Y879530D02*
G03Y887404I0J3937D01*
G01X156102Y847246D02*
G03X160039Y851183I0J3937D01*
G01Y875593D02*
Y851183D01*
G01X163976Y879530D02*
G03X160039Y875593I0J-3937D01*
G01X223031Y879530D02*
X163976D01*
G01X146064Y887404D02*
X230906D01*
G01X146064D02*
G03X142127Y883467I0J-3937D01*
G01X206102Y79528D02*
G03Y71654I0J-3937D01*
G01X226969Y67717D02*
G03X223031Y71654I-3937J0D01*
G01X226969Y43307D02*
Y67717D01*
G01Y43307D02*
G03X230906Y39370I3937J0D01*
G01X282283D02*
X230906D01*
G01X234843Y75591D02*
G03X230906Y79528I-3937J0D01*
G01X196309Y122835D02*
G03Y130709I0J3937D01*
G01X221506D02*
G03Y122835I0J-3937D01*
G01X234843Y210237D02*
G03X230906Y214174I-3937J0D01*
G01X206102D02*
G03Y206300I0J-3937D01*
G01X226969Y202363D02*
G03X223031Y206300I-3937J0D01*
G01X226969Y177953D02*
Y202363D01*
G01Y177953D02*
G03X230906Y174016I3937J0D01*
G01X282283D02*
X230906D01*
G01X196309Y257481D02*
G03Y265355I0J3937D01*
G01X221506D02*
G03Y257481I0J-3937D01*
G01X226969Y312599D02*
G03X230906Y308662I3937J0D01*
G01X282283D02*
X230906D01*
G01X234843Y344883D02*
G03X230906Y348820I-3937J0D01*
G01X206102D02*
G03Y340946I0J-3937D01*
G01X226969Y337009D02*
G03X223031Y340946I-3937J0D01*
G01X226969Y312599D02*
Y337009D01*
G01X196309Y392127D02*
G03Y400001I0J3937D01*
G01X221506D02*
G03Y392127I0J-3937D01*
G01X226969Y447245D02*
Y471655D01*
G01Y447245D02*
G03X230906Y443308I3937J0D01*
G01X282283D02*
X230906D01*
G01X234843Y479529D02*
G03X230906Y483466I-3937J0D01*
G01X206102D02*
G03Y475592I0J-3937D01*
G01X226969Y471655D02*
G03X223031Y475592I-3937J0D01*
G01X196309Y526773D02*
G03Y534647I0J3937D01*
G01X221506D02*
G03Y526773I0J-3937D01*
G01X226969Y581891D02*
Y606301D01*
G01Y581891D02*
G03X230906Y577954I3937J0D01*
G01X282283D02*
X230906D01*
G01X234843Y614175D02*
G03X230906Y618112I-3937J0D01*
G01X206102D02*
G03Y610238I0J-3937D01*
G01X226969Y606301D02*
G03X223031Y610238I-3937J0D01*
G01X196309Y661419D02*
G03Y669293I0J3937D01*
G01X221506D02*
G03Y661419I0J-3937D01*
G01X226969Y716537D02*
Y740947D01*
G01Y716537D02*
G03X230906Y712600I3937J0D01*
G01X282283D02*
X230906D01*
G01X234843Y748821D02*
G03X230906Y752758I-3937J0D01*
G01X206102D02*
G03Y744884I0J-3937D01*
G01X226969Y740947D02*
G03X223031Y744884I-3937J0D01*
G01X196309Y796065D02*
G03Y803939I0J3937D01*
G01X221506D02*
G03Y796065I0J-3937D01*
G01X206102Y887404D02*
G03Y879530I0J-3937D01*
G01X226969Y875593D02*
G03X223031Y879530I-3937J0D01*
G01X226969Y851183D02*
Y875593D01*
G01Y851183D02*
G03X230906Y847246I3937J0D01*
G01X282283D02*
X230906D01*
G01X234843Y883467D02*
G03X230906Y887404I-3937J0D01*
G01X266339Y55118D02*
Y75591D01*
G01X262402Y51181D02*
G03X266339Y55118I0J3937D01*
G01X238780Y51181D02*
X262402D01*
G01X234843Y55118D02*
G03X238780Y51181I3937J0D01*
G01X234843Y75591D02*
Y55118D01*
G01X270276Y79528D02*
X355119D01*
G01X270276D02*
G03X266339Y75591I0J-3937D01*
G01X270276Y214174D02*
X355119D01*
G01X270276D02*
G03X266339Y210237I0J-3937D01*
G01Y189764D02*
Y210237D01*
G01X262402Y185827D02*
G03X266339Y189764I0J3937D01*
G01X238780Y185827D02*
X262402D01*
G01X234843Y189764D02*
G03X238780Y185827I3937J0D01*
G01X234843Y210237D02*
Y189764D01*
G01X270276Y348820D02*
X355119D01*
G01X270276D02*
G03X266339Y344883I0J-3937D01*
G01Y324410D02*
Y344883D01*
G01X262402Y320473D02*
G03X266339Y324410I0J3937D01*
G01X238780Y320473D02*
X262402D01*
G01X234843Y324410D02*
G03X238780Y320473I3937J0D01*
G01X234843Y344883D02*
Y324410D01*
G01X270276Y483466D02*
X355119D01*
G01X270276D02*
G03X266339Y479529I0J-3937D01*
G01Y459056D02*
Y479529D01*
G01X262402Y455119D02*
G03X266339Y459056I0J3937D01*
G01X238780Y455119D02*
X262402D01*
G01X234843Y459057D02*
G03X238780Y455120I3937J0D01*
G01X234843Y479529D02*
Y459056D01*
G01X266339Y593702D02*
Y614175D01*
G01X262402Y589765D02*
G03X266339Y593702I0J3937D01*
G01X238780Y589765D02*
X262402D01*
G01X234843Y593703D02*
G03X238780Y589766I3937J0D01*
G01X234843Y614175D02*
Y593702D01*
G01X270276Y618112D02*
X355119D01*
G01X270276D02*
G03X266339Y614175I0J-3937D01*
G01Y728348D02*
Y748821D01*
G01X262402Y724411D02*
G03X266339Y728348I0J3937D01*
G01X238780Y724411D02*
X262402D01*
G01X234843Y728349D02*
G03X238780Y724412I3937J0D01*
G01X234843Y748821D02*
Y728348D01*
G01X270276Y752758D02*
X355119D01*
G01X270276D02*
G03X266339Y748821I0J-3937D01*
G01Y862994D02*
Y883467D01*
G01X262402Y859057D02*
G03X266339Y862994I0J3937D01*
G01X238780Y859057D02*
X262402D01*
G01X234843Y862995D02*
G03X238780Y859058I3937J0D01*
G01X234843Y883467D02*
Y862994D01*
G01X270276Y887404D02*
X355119D01*
G01X270276D02*
G03X266339Y883467I0J-3937D01*
G01X306969Y19685D02*
G03X296969I-5000J0D01*
G01D02*
G03X306969I5000J0D01*
G01X325788Y39370D02*
G03Y47244I0J3937D01*
G01Y71654D02*
G03Y79528I0J3937D01*
G01X325591Y71654D02*
X325788D01*
G01X325591Y47244D02*
Y71654D01*
G01X325788Y47244D02*
X325591D01*
G01X282283Y39370D02*
G03X286220Y43307I0J3937D01*
G01Y63780D02*
Y43307D01*
G01X290157Y67717D02*
G03X286220Y63780I0J-3937D01*
G01X313780Y67717D02*
X290157D01*
G01X317717Y63780D02*
G03X313780Y67717I-3937J0D01*
G01X317717Y43307D02*
Y63780D01*
G01Y43307D02*
G03X321654Y39370I3937J0D01*
G01X406496D02*
X321654D01*
G01X307265Y99213D02*
G03X317343I5039J0D01*
G01D02*
G03X307265I-5039J0D01*
G01X306969Y154331D02*
G03X296969I-5000J0D01*
G01D02*
G03X306969I5000J0D01*
G01X325788Y174016D02*
G03Y181890I0J3937D01*
G01Y206300D02*
G03Y214174I0J3937D01*
G01X325591Y206300D02*
X325788D01*
G01X325591Y181890D02*
Y206300D01*
G01X325788Y181890D02*
X325591D01*
G01X282283Y174016D02*
G03X286220Y177953I0J3937D01*
G01Y198426D02*
Y177953D01*
G01X290157Y202363D02*
G03X286220Y198426I0J-3937D01*
G01X313780Y202363D02*
X290157D01*
G01X317717Y198426D02*
G03X313780Y202363I-3937J0D01*
G01X317717Y177953D02*
Y198426D01*
G01Y177953D02*
G03X321654Y174016I3937J0D01*
G01X406496D02*
X321654D01*
G01X307265Y233859D02*
G03X317343I5039J0D01*
G01D02*
G03X307265I-5039J0D01*
G01X325788Y308662D02*
G03Y316536I0J3937D01*
G01X306969Y288977D02*
G03X296969I-5000J0D01*
G01D02*
G03X306969I5000J0D01*
G01X282283Y308662D02*
G03X286220Y312599I0J3937D01*
G01X317717D02*
G03X321654Y308662I3937J0D01*
G01X406496D02*
X321654D01*
G01X325788Y340946D02*
G03Y348820I0J3937D01*
G01X325591Y340946D02*
X325788D01*
G01X325591Y316536D02*
Y340946D01*
G01X325788Y316536D02*
X325591D01*
G01X286220Y333072D02*
Y312599D01*
G01X290157Y337009D02*
G03X286220Y333072I0J-3937D01*
G01X313780Y337009D02*
X290157D01*
G01X317717Y333072D02*
G03X313780Y337009I-3937J0D01*
G01X317717Y312599D02*
Y333072D01*
G01X307265Y368505D02*
G03X317343I5039J0D01*
G01D02*
G03X307265I-5039J0D01*
G01X325788Y443308D02*
G03Y451182I0J3937D01*
G01X325591D02*
Y475592D01*
G01X325788Y451182D02*
X325591D01*
G01X306969Y423623D02*
G03X296969I-5000J0D01*
G01D02*
G03X306969I5000J0D01*
G01X282283Y443308D02*
G03X286220Y447245I0J3937D01*
G01Y467718D02*
Y447245D01*
G01X317717D02*
Y467718D01*
G01Y447245D02*
G03X321654Y443308I3937J0D01*
G01X406496D02*
X321654D01*
G01X307265Y503151D02*
G03X317343I5039J0D01*
G01X325788Y475592D02*
G03Y483466I0J3937D01*
G01X325591Y475592D02*
X325788D01*
G01X290157Y471655D02*
G03X286220Y467718I0J-3937D01*
G01X313780Y471655D02*
X290157D01*
G01X317717Y467718D02*
G03X313780Y471655I-3937J0D01*
G01X317343Y503151D02*
G03X307265I-5039J0D01*
G01X325788Y577954D02*
G03Y585828I0J3937D01*
G01X325591D02*
Y610238D01*
G01X325788Y585828D02*
X325591D01*
G01X306969Y558269D02*
G03X296969I-5000J0D01*
G01D02*
G03X306969I5000J0D01*
G01X282283Y577954D02*
G03X286220Y581891I0J3937D01*
G01Y602364D02*
Y581891D01*
G01X317717D02*
Y602364D01*
G01Y581891D02*
G03X321654Y577954I3937J0D01*
G01X406496D02*
X321654D01*
G01X307265Y637797D02*
G03X317343I5039J0D01*
G01D02*
G03X307265I-5039J0D01*
G01X325788Y610238D02*
G03Y618112I0J3937D01*
G01X325591Y610238D02*
X325788D01*
G01X290157Y606301D02*
G03X286220Y602364I0J-3937D01*
G01X313780Y606301D02*
X290157D01*
G01X317717Y602364D02*
G03X313780Y606301I-3937J0D01*
G01X296969Y692915D02*
G03X306969I5000J0D01*
G01X325788Y712600D02*
G03Y720474I0J3937D01*
G01X325591D02*
Y744884D01*
G01X325788Y720474D02*
X325591D01*
G01X306969Y692915D02*
G03X296969I-5000J0D01*
G01X282283Y712600D02*
G03X286220Y716537I0J3937D01*
G01Y737010D02*
Y716537D01*
G01X290157Y740947D02*
G03X286220Y737010I0J-3937D01*
G01X317717Y737011D02*
G03X313780Y740947I-3937J-1D01*
G01X317717Y716537D02*
Y737010D01*
G01Y716537D02*
G03X321654Y712600I3937J0D01*
G01X406496D02*
X321654D01*
G01X307265Y772443D02*
G03X317343I5039J0D01*
G01D02*
G03X307265I-5039J0D01*
G01X325788Y744884D02*
G03Y752758I0J3937D01*
G01X325591Y744884D02*
X325788D01*
G01X313780Y740947D02*
X290157D01*
G01X306969Y827561D02*
G03X296969I-5000J0D01*
G01D02*
G03X306969I5000J0D01*
G01X325788Y847246D02*
G03Y855120I0J3937D01*
G01Y879530D02*
G03Y887404I0J3937D01*
G01X325591Y879530D02*
X325788D01*
G01X325591Y855120D02*
Y879530D01*
G01X325788Y855120D02*
X325591D01*
G01X282283Y847246D02*
G03X286220Y851183I0J3937D01*
G01Y871656D02*
Y851183D01*
G01X290157Y875593D02*
G03X286220Y871656I0J-3937D01*
G01X313780Y875593D02*
X290157D01*
G01X317717Y871657D02*
G03X313780Y875593I-3937J-1D01*
G01X317717Y851183D02*
Y871656D01*
G01Y851183D02*
G03X321654Y847246I3937J0D01*
G01X406496D02*
X321654D01*
G01X307265Y907089D02*
G03X317343I5039J0D01*
G01D02*
G03X307265I-5039J0D01*
G01X362993Y51181D02*
X386615D01*
G01X359056Y55118D02*
G03X362993Y51181I3937J0D01*
G01X359056Y75591D02*
Y55118D01*
G01X350985Y71654D02*
X351182D01*
G01X350985Y47244D02*
X351182D01*
G01X350985D02*
G03Y39370I0J-3937D01*
G01Y79528D02*
G03Y71654I0J-3937D01*
G01X351182D02*
Y47244D01*
G01X359056Y75591D02*
G03X355119Y79528I-3937J0D01*
G01X362993Y185827D02*
X386615D01*
G01X359056Y189764D02*
G03X362993Y185827I3937J0D01*
G01X359056Y210237D02*
Y189764D01*
G01Y210237D02*
G03X355119Y214174I-3937J0D01*
G01X350985Y206300D02*
X351182D01*
G01X350985Y181890D02*
X351182D01*
G01X350985D02*
G03Y174016I0J-3937D01*
G01Y214174D02*
G03Y206300I0J-3937D01*
G01X351182D02*
Y181890D01*
G01X350985Y316536D02*
G03Y308662I0J-3937D01*
G01X362993Y320473D02*
X386615D01*
G01X359056Y324410D02*
G03X362993Y320473I3937J0D01*
G01X359056Y344883D02*
Y324410D01*
G01Y344883D02*
G03X355119Y348820I-3937J0D01*
G01X350985Y340946D02*
X351182D01*
G01X350985Y316536D02*
X351182D01*
G01X350985Y348820D02*
G03Y340946I0J-3937D01*
G01X351182D02*
Y316536D01*
G01X350985Y451182D02*
X351182D01*
G01X350985D02*
G03Y443308I0J-3937D01*
G01X351182Y475592D02*
Y451182D01*
G01X362993Y455119D02*
X386615D01*
G01X359056Y459056D02*
G03X362993Y455119I3937J0D01*
G01X359056Y479529D02*
Y459056D01*
G01Y479529D02*
G03X355119Y483466I-3937J0D01*
G01X350985Y475592D02*
X351182D01*
G01X350985Y483466D02*
G03Y475592I0J-3937D01*
G01X362993Y589765D02*
X386615D01*
G01X359056Y593702D02*
G03X362993Y589765I3937J0D01*
G01X359056Y614175D02*
Y593702D01*
G01X350985Y585828D02*
X351182D01*
G01X350985D02*
G03Y577954I0J-3937D01*
G01X351182Y610238D02*
Y585828D01*
G01X359056Y614175D02*
G03X355119Y618112I-3937J0D01*
G01X350985Y610238D02*
X351182D01*
G01X350985Y618112D02*
G03Y610238I0J-3937D01*
G01X362993Y724411D02*
X386615D01*
G01X359056Y728349D02*
G03X362993Y724412I3937J0D01*
G01X359056Y748821D02*
Y728348D01*
G01X350985Y720474D02*
X351182D01*
G01X350985D02*
G03Y712600I0J-3937D01*
G01X351182Y744884D02*
Y720474D01*
G01X359056Y748821D02*
G03X355119Y752758I-3937J0D01*
G01X350985Y744884D02*
X351182D01*
G01X350985Y752758D02*
G03Y744884I0J-3937D01*
G01X362993Y859057D02*
X386615D01*
G01X359056Y862995D02*
G03X362993Y859058I3937J0D01*
G01X359056Y883467D02*
Y862994D01*
G01X350985Y879530D02*
X351182D01*
G01X350985Y855120D02*
X351182D01*
G01X350985D02*
G03Y847246I0J-3937D01*
G01Y887404D02*
G03Y879530I0J-3937D01*
G01X351182D02*
Y855120D01*
G01X359056Y883467D02*
G03X355119Y887404I-3937J0D01*
G01X390552Y55118D02*
Y75591D01*
G01X386615Y51181D02*
G03X390552Y55118I0J3937D01*
G01X406496Y39370D02*
G03X410433Y43307I0J3937D01*
G01Y63780D02*
Y43307D01*
G01X414370Y67717D02*
G03X410433Y63780I0J-3937D01*
G01X437992Y67717D02*
X414370D01*
G01X394489Y79528D02*
X479331D01*
G01X394489D02*
G03X390552Y75591I0J-3937D01*
G01X387894Y122835D02*
G03Y130709I0J3937D01*
G01X413091D02*
G03Y122835I0J-3937D01*
G01X394489Y214174D02*
X479331D01*
G01X394489D02*
G03X390552Y210237I0J-3937D01*
G01Y189764D02*
Y210237D01*
G01X386615Y185827D02*
G03X390552Y189764I0J3937D01*
G01X406496Y174016D02*
G03X410433Y177953I0J3937D01*
G01Y198426D02*
Y177953D01*
G01X414370Y202363D02*
G03X410433Y198426I0J-3937D01*
G01X437992Y202363D02*
X414370D01*
G01X387894Y257481D02*
G03Y265355I0J3937D01*
G01X413091D02*
G03Y257481I0J-3937D01*
G01X406496Y308662D02*
G03X410433Y312599I0J3937D01*
G01X394489Y348820D02*
X479331D01*
G01X394489D02*
G03X390552Y344883I0J-3937D01*
G01Y324410D02*
Y344883D01*
G01X386615Y320473D02*
G03X390552Y324410I0J3937D01*
G01X410433Y333072D02*
Y312599D01*
G01X414370Y337009D02*
G03X410433Y333072I0J-3937D01*
G01X437992Y337009D02*
X414370D01*
G01X387894Y392127D02*
G03Y400001I0J3937D01*
G01X413091D02*
G03Y392127I0J-3937D01*
G01X406496Y443308D02*
G03X410433Y447245I0J3937D01*
G01Y467718D02*
Y447245D01*
G01X394489Y483466D02*
X479331D01*
G01X394489D02*
G03X390552Y479529I0J-3937D01*
G01Y459056D02*
Y479529D01*
G01X386615Y455119D02*
G03X390552Y459056I0J3937D01*
G01X414370Y471655D02*
G03X410433Y467718I0J-3937D01*
G01X437992Y471655D02*
X414370D01*
G01X387894Y526773D02*
G03Y534647I0J3937D01*
G01X413091D02*
G03Y526773I0J-3937D01*
G01X390552Y593702D02*
Y614175D01*
G01X386615Y589765D02*
G03X390552Y593702I0J3937D01*
G01X406496Y577954D02*
G03X410433Y581891I0J3937D01*
G01Y602364D02*
Y581891D01*
G01X394489Y618112D02*
X479331D01*
G01X394489D02*
G03X390552Y614175I0J-3937D01*
G01X414370Y606301D02*
G03X410433Y602364I0J-3937D01*
G01X437992Y606301D02*
X414370D01*
G01X387894Y661419D02*
G03Y669293I0J3937D01*
G01X413091D02*
G03Y661419I0J-3937D01*
G01X390552Y728348D02*
Y748821D01*
G01X386615Y724412D02*
G03X390552Y728349I0J3937D01*
G01X406496Y712600D02*
G03X410433Y716537I0J3937D01*
G01Y737010D02*
Y716537D01*
G01X414370Y740947D02*
G03X410433Y737010I0J-3937D01*
G01X394489Y752758D02*
X479331D01*
G01X394489D02*
G03X390552Y748821I0J-3937D01*
G01X437992Y740947D02*
X414370D01*
G01X387894Y796065D02*
G03Y803939I0J3937D01*
G01X413091D02*
G03Y796065I0J-3937D01*
G01X390552Y862994D02*
Y883467D01*
G01X386615Y859058D02*
G03X390552Y862995I0J3937D01*
G01X406496Y847246D02*
G03X410433Y851183I0J3937D01*
G01Y871656D02*
Y851183D01*
G01X414370Y875593D02*
G03X410433Y871656I0J-3937D01*
G01X437992Y875593D02*
X414370D01*
G01X394489Y887404D02*
X479331D01*
G01X394489D02*
G03X390552Y883467I0J-3937D01*
G01X450000Y47244D02*
X449803D01*
G01X450000Y71654D02*
X449803D01*
G01X450000D02*
G03Y79528I0J3937D01*
G01Y39370D02*
G03Y47244I0J3937D01*
G01X449803D02*
Y71654D01*
G01X441929Y63780D02*
G03X437992Y67717I-3937J0D01*
G01X441929Y43307D02*
Y63780D01*
G01Y43307D02*
G03X445866Y39370I3937J0D01*
G01X530709D02*
X445866D01*
G01X450000Y181890D02*
X449803D01*
G01X450000Y206300D02*
X449803D01*
G01X450000D02*
G03Y214174I0J3937D01*
G01Y174016D02*
G03Y181890I0J3937D01*
G01X449803D02*
Y206300D01*
G01X441929Y198426D02*
G03X437992Y202363I-3937J0D01*
G01X441929Y177953D02*
Y198426D01*
G01Y177953D02*
G03X445866Y174016I3937J0D01*
G01X530709D02*
X445866D01*
G01X450000Y308662D02*
G03Y316536I0J3937D01*
G01X441929Y312599D02*
G03X445866Y308662I3937J0D01*
G01X530709D02*
X445866D01*
G01X450000Y316536D02*
X449803D01*
G01X450000Y340946D02*
X449803D01*
G01X450000D02*
G03Y348820I0J3937D01*
G01X449803Y316536D02*
Y340946D01*
G01X441929Y333072D02*
G03X437992Y337009I-3937J0D01*
G01X441929Y312599D02*
Y333072D01*
G01X450000Y451182D02*
X449803D01*
G01X450000Y443308D02*
G03Y451182I0J3937D01*
G01X449803D02*
Y475592D01*
G01X441929Y447245D02*
Y467718D01*
G01Y447245D02*
G03X445866Y443308I3937J0D01*
G01X530709D02*
X445866D01*
G01X450000Y475592D02*
X449803D01*
G01X450000D02*
G03Y483466I0J3937D01*
G01X441929Y467718D02*
G03X437992Y471655I-3937J0D01*
G01X450000Y585828D02*
X449803D01*
G01X450000Y577954D02*
G03Y585828I0J3937D01*
G01X449803D02*
Y610238D01*
G01X441929Y581891D02*
Y602364D01*
G01Y581891D02*
G03X445866Y577954I3937J0D01*
G01X530709D02*
X445866D01*
G01X450000Y610238D02*
X449803D01*
G01X450000D02*
G03Y618112I0J3937D01*
G01X441929Y602364D02*
G03X437992Y606301I-3937J0D01*
G01X450000Y720474D02*
X449803D01*
G01X450000Y712600D02*
G03Y720474I0J3937D01*
G01X449803D02*
Y744884D01*
G01X441929Y737010D02*
G03X437992Y740947I-3937J0D01*
G01X441929Y716537D02*
Y737010D01*
G01Y716537D02*
G03X445866Y712600I3937J0D01*
G01X530709D02*
X445866D01*
G01X450000Y744884D02*
X449803D01*
G01X450000D02*
G03Y752758I0J3937D01*
G01Y855120D02*
X449803D01*
G01X450000Y879530D02*
X449803D01*
G01X450000D02*
G03Y887404I0J3937D01*
G01Y847246D02*
G03Y855120I0J3937D01*
G01X449803D02*
Y879530D01*
G01X441929Y871656D02*
G03X437992Y875593I-3937J0D01*
G01X441929Y851183D02*
Y871656D01*
G01Y851183D02*
G03X445866Y847246I3937J0D01*
G01X530709D02*
X445866D01*
G01X493720Y19685D02*
G03X483642I-5039J0D01*
G01D02*
G03X493720I5039J0D01*
G01X514765Y55118D02*
Y75591D01*
G01X510828Y51181D02*
G03X514765Y55118I0J3937D01*
G01X487205Y51181D02*
X510828D01*
G01X483269Y55118D02*
G03X487205Y51182I3937J1D01*
G01X483268Y75591D02*
Y55118D01*
G01X475197Y79528D02*
G03Y71654I0J-3937D01*
G01Y47244D02*
G03Y39370I0J-3937D01*
G01X475394Y47244D02*
X475197D01*
G01X475394Y71654D02*
Y47244D01*
G01X475197Y71654D02*
X475394D01*
G01X494017Y99213D02*
G03X504017I5000J0D01*
G01D02*
G03X494017I-5000J0D01*
G01X518702Y79528D02*
X570079D01*
G01X518702D02*
G03X514765Y75591I0J-3937D01*
G01X483268D02*
G03X479331Y79528I-3937J0D01*
G01X493720Y154331D02*
G03X483642I-5039J0D01*
G01D02*
G03X493720I5039J0D01*
G01X518702Y214174D02*
X570079D01*
G01X518702D02*
G03X514765Y210237I0J-3937D01*
G01Y189764D02*
Y210237D01*
G01X510828Y185827D02*
G03X514765Y189764I0J3937D01*
G01X487205Y185827D02*
X510828D01*
G01X483269Y189764D02*
G03X487205Y185828I3937J1D01*
G01X483268Y210237D02*
Y189764D01*
G01Y210237D02*
G03X479331Y214174I-3937J0D01*
G01X475197D02*
G03Y206300I0J-3937D01*
G01Y181890D02*
G03Y174016I0J-3937D01*
G01X475394Y181890D02*
X475197D01*
G01X475394Y206300D02*
Y181890D01*
G01X475197Y206300D02*
X475394D01*
G01X494017Y233859D02*
G03X504017I5000J0D01*
G01D02*
G03X494017I-5000J0D01*
G01X475197Y316536D02*
G03Y308662I0J-3937D01*
G01X493720Y288977D02*
G03X483642I-5039J0D01*
G01D02*
G03X493720I5039J0D01*
G01X518702Y348820D02*
X570079D01*
G01X518702D02*
G03X514765Y344883I0J-3937D01*
G01Y324410D02*
Y344883D01*
G01X510828Y320473D02*
G03X514765Y324410I0J3937D01*
G01X487205Y320473D02*
X510828D01*
G01X483269Y324410D02*
G03X487205Y320474I3937J1D01*
G01X483268Y344883D02*
Y324410D01*
G01Y344883D02*
G03X479331Y348820I-3937J0D01*
G01X475197D02*
G03Y340946I0J-3937D01*
G01X475394Y316536D02*
X475197D01*
G01X475394Y340946D02*
Y316536D01*
G01X475197Y340946D02*
X475394D01*
G01X494017Y368505D02*
G03X504017I5000J0D01*
G01D02*
G03X494017I-5000J0D01*
G01X475197Y451182D02*
G03Y443308I0J-3937D01*
G01X475394Y451182D02*
X475197D01*
G01X475394Y475592D02*
Y451182D01*
G01X493720Y423623D02*
G03X483642I-5039J0D01*
G01D02*
G03X493720I5039J0D01*
G01X494017Y503151D02*
G03X504017I5000J0D01*
G01X518702Y483466D02*
X570079D01*
G01X518702D02*
G03X514765Y479529I0J-3937D01*
G01Y459056D02*
Y479529D01*
G01X510828Y455120D02*
G03X514765Y459057I0J3937D01*
G01X487205Y455119D02*
X510828D01*
G01X483269Y459056D02*
G03X487205Y455120I3937J1D01*
G01X483268Y479529D02*
Y459056D01*
G01Y479529D02*
G03X479331Y483466I-3937J0D01*
G01X475197D02*
G03Y475592I0J-3937D01*
G01D02*
X475394D01*
G01X504017Y503151D02*
G03X494017I-5000J0D01*
G01X514765Y593702D02*
Y614175D01*
G01X510828Y589766D02*
G03X514765Y593703I0J3937D01*
G01X487205Y589765D02*
X510828D01*
G01X483269Y593702D02*
G03X487205Y589766I3937J1D01*
G01X483268Y614175D02*
Y593702D01*
G01X475197Y585828D02*
G03Y577954I0J-3937D01*
G01X475394Y585828D02*
X475197D01*
G01X475394Y610238D02*
Y585828D01*
G01X493720Y558269D02*
G03X483642I-5039J0D01*
G01D02*
G03X493720I5039J0D01*
G01X494017Y637797D02*
G03X504017I5000J0D01*
G01D02*
G03X494017I-5000J0D01*
G01X518702Y618112D02*
X570079D01*
G01X518702D02*
G03X514765Y614175I0J-3937D01*
G01X483268D02*
G03X479331Y618112I-3937J0D01*
G01X475197D02*
G03Y610238I0J-3937D01*
G01D02*
X475394D01*
G01X483642Y692915D02*
G03X493720I5039J0D01*
G01X514765Y728348D02*
Y748821D01*
G01X510828Y724412D02*
G03X514765Y728349I0J3937D01*
G01X487205Y724411D02*
X510828D01*
G01X483269Y728348D02*
G03X487205Y724412I3937J1D01*
G01X483268Y748821D02*
Y728348D01*
G01X475197Y720474D02*
G03Y712600I0J-3937D01*
G01X475394Y720474D02*
X475197D01*
G01X475394Y744884D02*
Y720474D01*
G01X493720Y692915D02*
G03X483642I-5039J0D01*
G01X494017Y772443D02*
G03X504017I5000J0D01*
G01D02*
G03X494017I-5000J0D01*
G01X518702Y752758D02*
X570079D01*
G01X518702D02*
G03X514765Y748821I0J-3937D01*
G01X483268D02*
G03X479331Y752758I-3937J0D01*
G01X475197D02*
G03Y744884I0J-3937D01*
G01D02*
X475394D01*
G01X493720Y827561D02*
G03X483642I-5039J0D01*
G01D02*
G03X493720I5039J0D01*
G01X514765Y862994D02*
Y883467D01*
G01X510828Y859058D02*
G03X514765Y862995I0J3937D01*
G01X487205Y859057D02*
X510828D01*
G01X483269Y862994D02*
G03X487205Y859058I3937J1D01*
G01X483268Y883467D02*
Y862994D01*
G01X475197Y887404D02*
G03Y879530I0J-3937D01*
G01Y855120D02*
G03Y847246I0J-3937D01*
G01X475394Y855120D02*
X475197D01*
G01X475394Y879530D02*
Y855120D01*
G01X475197Y879530D02*
X475394D01*
G01X494017Y907089D02*
G03X504017I5000J0D01*
G01D02*
G03X494017I-5000J0D01*
G01X518702Y887404D02*
X570079D01*
G01X518702D02*
G03X514765Y883467I0J-3937D01*
G01X483268D02*
G03X479331Y887404I-3937J0D01*
G01X530709Y39370D02*
G03X534646Y43307I0J3937D01*
G01Y63780D02*
Y43307D01*
G01X538583Y67717D02*
G03X534646Y63780I0J-3937D01*
G01X562205Y67717D02*
X538583D01*
G01X566142Y63780D02*
G03X562205Y67717I-3937J0D01*
G01X566142Y43307D02*
Y63780D01*
G01Y43307D02*
G03X570079Y39370I3937J0D01*
G01X530709Y174016D02*
G03X534646Y177953I0J3937D01*
G01Y198426D02*
Y177953D01*
G01X538583Y202363D02*
G03X534646Y198426I0J-3937D01*
G01X562205Y202363D02*
X538583D01*
G01X566142Y198426D02*
G03X562205Y202363I-3937J0D01*
G01X566142Y177953D02*
Y198426D01*
G01Y177953D02*
G03X570079Y174016I3937J0D01*
G01X530709Y308662D02*
G03X534646Y312599I0J3937D01*
G01Y333072D02*
Y312599D01*
G01X538583Y337009D02*
G03X534646Y333072I0J-3937D01*
G01X562205Y337009D02*
X538583D01*
G01X566142Y333072D02*
G03X562205Y337009I-3937J0D01*
G01X566142Y312599D02*
Y333072D01*
G01Y312599D02*
G03X570079Y308662I3937J0D01*
G01X530709Y443308D02*
G03X534646Y447245I0J3937D01*
G01Y467718D02*
Y447245D01*
G01X566142D02*
Y467718D01*
G01Y447245D02*
G03X570079Y443308I3937J0D01*
G01X538583Y471655D02*
G03X534646Y467718I0J-3937D01*
G01X562205Y471655D02*
X538583D01*
G01X566142Y467718D02*
G03X562205Y471655I-3937J0D01*
G01X530709Y577954D02*
G03X534646Y581891I0J3937D01*
G01Y602364D02*
Y581891D01*
G01X566142D02*
Y602364D01*
G01Y581891D02*
G03X570079Y577954I3937J0D01*
G01X538583Y606301D02*
G03X534646Y602364I0J-3937D01*
G01X562205Y606301D02*
X538583D01*
G01X566142Y602364D02*
G03X562205Y606301I-3937J0D01*
G01X530709Y712601D02*
G03X534646Y716538I0J3937D01*
G01Y737010D02*
Y716537D01*
G01X538583Y740947D02*
G03X534646Y737010I0J-3937D01*
G01X566142D02*
G03X562205Y740947I-3937J0D01*
G01X566142Y716537D02*
Y737010D01*
G01Y716537D02*
G03X570079Y712600I3937J0D01*
G01X562205Y740947D02*
X538583D01*
G01X530709Y847247D02*
G03X534646Y851184I0J3937D01*
G01Y871656D02*
Y851183D01*
G01X538583Y875593D02*
G03X534646Y871656I0J-3937D01*
G01X562205Y875593D02*
X538583D01*
G01X566142Y871656D02*
G03X562205Y875593I-3937J0D01*
G01X566142Y851183D02*
Y871656D01*
G01Y851183D02*
G03X570079Y847246I3937J0D01*
G01X577954Y47244D02*
X637009D01*
G01X574016Y51181D02*
G03X577954Y47244I3937J0D01*
G01X574016Y75591D02*
Y51181D01*
G01X594883Y39370D02*
G03Y47244I0J3937D01*
G01X654921Y39370D02*
X570079D01*
G01X574016Y75591D02*
G03X570079Y79528I-3937J0D01*
G01X604676Y130709D02*
G03Y122835I0J-3937D01*
G01X579479D02*
G03Y130709I0J3937D01*
G01X577954Y181890D02*
X637009D01*
G01X574016Y185827D02*
G03X577954Y181890I3937J0D01*
G01X574016Y210237D02*
Y185827D01*
G01Y210237D02*
G03X570079Y214174I-3937J0D01*
G01X594883Y174016D02*
G03Y181890I0J3937D01*
G01X654921Y174016D02*
X570079D01*
G01X604676Y265355D02*
G03Y257481I0J-3937D01*
G01X579479D02*
G03Y265355I0J3937D01*
G01X594883Y308662D02*
G03Y316536I0J3937D01*
G01X654921Y308662D02*
X570079D01*
G01X577954Y316536D02*
X637009D01*
G01X574016Y320473D02*
G03X577954Y316536I3937J0D01*
G01X574016Y344883D02*
Y320473D01*
G01Y344883D02*
G03X570079Y348820I-3937J0D01*
G01X604676Y400001D02*
G03Y392127I0J-3937D01*
G01X579479D02*
G03Y400001I0J3937D01*
G01X577954Y451182D02*
X637009D01*
G01X574016Y455120D02*
G03X577954Y451183I3937J0D01*
G01X594883Y443308D02*
G03Y451182I0J3937D01*
G01X654921Y443308D02*
X570079D01*
G01X574016Y479529D02*
Y455119D01*
G01Y479529D02*
G03X570079Y483466I-3937J0D01*
G01X604676Y534647D02*
G03Y526773I0J-3937D01*
G01X579479D02*
G03Y534647I0J3937D01*
G01X577954Y585828D02*
X637009D01*
G01X574016Y589766D02*
G03X577954Y585829I3937J0D01*
G01X574016Y614175D02*
Y589765D01*
G01X594883Y577954D02*
G03Y585828I0J3937D01*
G01X654921Y577954D02*
X570079D01*
G01X574016Y614175D02*
G03X570079Y618112I-3937J0D01*
G01X604676Y669293D02*
G03Y661419I0J-3937D01*
G01X579479D02*
G03Y669293I0J3937D01*
G01X577954Y720474D02*
X637009D01*
G01X574016Y724412D02*
G03X577954Y720475I3937J0D01*
G01X574016Y748821D02*
Y724411D01*
G01X594883Y712600D02*
G03Y720474I0J3937D01*
G01X654921Y712600D02*
X570079D01*
G01X574016Y748821D02*
G03X570079Y752758I-3937J0D01*
G01X604676Y803939D02*
G03Y796065I0J-3937D01*
G01X579479D02*
G03Y803939I0J3937D01*
G01X577954Y855120D02*
X637009D01*
G01X574016Y859058D02*
G03X577954Y855121I3937J0D01*
G01X574016Y883467D02*
Y859057D01*
G01X594883Y847246D02*
G03Y855120I0J3937D01*
G01X654921Y847246D02*
X570079D01*
G01X574016Y883467D02*
G03X570079Y887404I-3937J0D01*
G01X640946Y51181D02*
Y75591D01*
G01X637009Y47244D02*
G03X640946Y51181I0J3937D01*
G01X620080Y47244D02*
G03Y39370I0J-3937D01*
G01X654921D02*
G03X658858Y43307I0J3937D01*
G01Y63780D02*
Y43307D01*
G01X662795Y67717D02*
G03X658858Y63780I0J-3937D01*
G01X644883Y79528D02*
X727757D01*
G01X644883D02*
G03X640946Y75591I0J-3937D01*
G01X644883Y214174D02*
X727757D01*
G01X644883D02*
G03X640946Y210237I0J-3937D01*
G01Y185827D02*
Y210237D01*
G01X637009Y181890D02*
G03X640946Y185827I0J3937D01*
G01X620080Y181890D02*
G03Y174016I0J-3937D01*
G01X654921D02*
G03X658858Y177953I0J3937D01*
G01Y198426D02*
Y177953D01*
G01X662795Y202363D02*
G03X658858Y198426I0J-3937D01*
G01X620080Y316536D02*
G03Y308662I0J-3937D01*
G01X654921D02*
G03X658858Y312599I0J3937D01*
G01X644883Y348820D02*
X727757D01*
G01X644883D02*
G03X640946Y344883I0J-3937D01*
G01Y320473D02*
Y344883D01*
G01X637009Y316536D02*
G03X640946Y320473I0J3937D01*
G01X658858Y333072D02*
Y312599D01*
G01X662795Y337009D02*
G03X658858Y333072I0J-3937D01*
G01X637009Y451183D02*
G03X640946Y455120I0J3937D01*
G01X620080Y451182D02*
G03Y443308I0J-3937D01*
G01X654921D02*
G03X658858Y447245I0J3937D01*
G01Y467718D02*
Y447245D01*
G01X644883Y483466D02*
X727757D01*
G01X644883D02*
G03X640946Y479529I0J-3937D01*
G01Y455119D02*
Y479529D01*
G01X662795Y471655D02*
G03X658858Y467718I0J-3937D01*
G01X640946Y589765D02*
Y614175D01*
G01X637009Y585829D02*
G03X640946Y589766I0J3937D01*
G01X620080Y585828D02*
G03Y577954I0J-3937D01*
G01X654921D02*
G03X658858Y581891I0J3937D01*
G01Y602364D02*
Y581891D01*
G01X644883Y618112D02*
X727757D01*
G01X644883D02*
G03X640946Y614175I0J-3937D01*
G01X662795Y606301D02*
G03X658858Y602364I0J-3937D01*
G01X640946Y724411D02*
Y748821D01*
G01X637009Y720475D02*
G03X640946Y724412I0J3937D01*
G01X620080Y720474D02*
G03Y712600I0J-3937D01*
G01X654921D02*
G03X658858Y716537I0J3937D01*
G01Y737010D02*
Y716537D01*
G01X662795Y740947D02*
G03X658858Y737010I0J-3937D01*
G01X644883Y752758D02*
X727757D01*
G01X644883D02*
G03X640946Y748821I0J-3937D01*
G01Y859057D02*
Y883467D01*
G01X637009Y855121D02*
G03X640946Y859058I0J3937D01*
G01X620080Y855120D02*
G03Y847246I0J-3937D01*
G01X654921D02*
G03X658858Y851183I0J3937D01*
G01Y871656D02*
Y851183D01*
G01X662795Y875593D02*
G03X658858Y871656I0J-3937D01*
G01X644883Y887404D02*
X727757D01*
G01X644883D02*
G03X640946Y883467I0J-3937D01*
G01X686319Y19685D02*
G03X674902I-5708J0D01*
G01D02*
G03X686319I5708J0D01*
G01X717106D02*
G03X707106I-5000J0D01*
G01D02*
G03X717106I5000J0D01*
G01X701969Y39370D02*
G03Y47244I0J3937D01*
G01Y71654D02*
G03Y79528I0J3937D01*
G01X698228Y71654D02*
X701969D01*
G01X698228Y47244D02*
Y71654D01*
G01X701969Y47244D02*
X698228D01*
G01X686417Y67717D02*
X662795D01*
G01X690354Y63780D02*
G03X686417Y67717I-3937J0D01*
G01X690354Y43307D02*
Y63780D01*
G01Y43307D02*
G03X694291Y39370I3937J0D01*
G01X724409D02*
X694291D01*
G01X686319Y154331D02*
G03X674902I-5708J0D01*
G01D02*
G03X686319I5708J0D01*
G01X717106D02*
G03X707106I-5000J0D01*
G01D02*
G03X717106I5000J0D01*
G01X701969Y174016D02*
G03Y181890I0J3937D01*
G01Y206300D02*
G03Y214174I0J3937D01*
G01X698228Y206300D02*
X701969D01*
G01X698228Y181890D02*
Y206300D01*
G01X701969Y181890D02*
X698228D01*
G01X686417Y202363D02*
X662795D01*
G01X690354Y198426D02*
G03X686417Y202363I-3937J0D01*
G01X690354Y177953D02*
Y198426D01*
G01Y177953D02*
G03X694291Y174016I3937J0D01*
G01X724409D02*
X694291D01*
G01X701969Y308662D02*
G03Y316536I0J3937D01*
G01X686319Y288977D02*
G03X674902I-5708J0D01*
G01D02*
G03X686319I5708J0D01*
G01X717106D02*
G03X707106I-5000J0D01*
G01D02*
G03X717106I5000J0D01*
G01X690354Y312599D02*
G03X694291Y308662I3937J0D01*
G01X724409D02*
X694291D01*
G01X701969Y340946D02*
G03Y348820I0J3937D01*
G01X698228Y340946D02*
X701969D01*
G01X698228Y316536D02*
Y340946D01*
G01X701969Y316536D02*
X698228D01*
G01X686417Y337009D02*
X662795D01*
G01X690354Y333072D02*
G03X686417Y337009I-3937J0D01*
G01X690354Y312599D02*
Y333072D01*
G01X701969Y443308D02*
G03Y451182I0J3937D01*
G01X698228D02*
Y475592D01*
G01X701969Y451182D02*
X698228D01*
G01X686319Y423623D02*
G03X674902I-5708J0D01*
G01D02*
G03X686319I5708J0D01*
G01X717106D02*
G03X707106I-5000J0D01*
G01D02*
G03X717106I5000J0D01*
G01X690354Y447245D02*
Y467718D01*
G01Y447245D02*
G03X694291Y443308I3937J0D01*
G01X724409D02*
X694291D01*
G01X701969Y475592D02*
G03Y483466I0J3937D01*
G01X698228Y475592D02*
X701969D01*
G01X686417Y471655D02*
X662795D01*
G01X690354Y467718D02*
G03X686417Y471655I-3937J0D01*
G01X701969Y577954D02*
G03Y585828I0J3937D01*
G01X698228D02*
Y610238D01*
G01X701969Y585828D02*
X698228D01*
G01X686319Y558269D02*
G03X674902I-5708J0D01*
G01D02*
G03X686319I5708J0D01*
G01X717106D02*
G03X707106I-5000J0D01*
G01D02*
G03X717106I5000J0D01*
G01X690354Y581891D02*
Y602364D01*
G01Y581891D02*
G03X694291Y577954I3937J0D01*
G01X724409D02*
X694291D01*
G01X701969Y610238D02*
G03Y618112I0J3937D01*
G01X698228Y610238D02*
X701969D01*
G01X686417Y606301D02*
X662795D01*
G01X690354Y602364D02*
G03X686417Y606301I-3937J0D01*
G01X674902Y692915D02*
G03X686319I5708J0D01*
G01X707106D02*
G03X717106I5000J0D01*
G01X701969Y712600D02*
G03Y720474I0J3937D01*
G01X698228D02*
Y744884D01*
G01X701969Y720474D02*
X698228D01*
G01X686319Y692915D02*
G03X674902I-5708J0D01*
G01X717106D02*
G03X707106I-5000J0D01*
G01X690354Y737010D02*
G03X686417Y740947I-3937J0D01*
G01X690354Y716537D02*
Y737010D01*
G01Y716538D02*
G03X694291Y712601I3937J0D01*
G01X724409Y712600D02*
X694291D01*
G01X701969Y744884D02*
G03Y752758I0J3937D01*
G01X698228Y744884D02*
X701969D01*
G01X686417Y740947D02*
X662795D01*
G01X686319Y827561D02*
G03X674902I-5708J0D01*
G01D02*
G03X686319I5708J0D01*
G01X717106D02*
G03X707106I-5000J0D01*
G01D02*
G03X717106I5000J0D01*
G01X701969Y847246D02*
G03Y855120I0J3937D01*
G01Y879530D02*
G03Y887404I0J3937D01*
G01X698228Y879530D02*
X701969D01*
G01X698228Y855120D02*
Y879530D01*
G01X701969Y855120D02*
X698228D01*
G01X686417Y875593D02*
X662795D01*
G01X690354Y871656D02*
G03X686417Y875593I-3937J0D01*
G01X690354Y851183D02*
Y871656D01*
G01Y851184D02*
G03X694291Y847247I3937J0D01*
G01X724409Y847246D02*
X694291D01*
G01X736220Y0D02*
G03X740157Y-3937I3937J0D01*
G01X736220Y5118D02*
Y0D01*
G01X740157Y-3937D02*
X793111D01*
G01X736220Y5118D02*
G03X728346I-3937J0D01*
G01X724409Y-3937D02*
G03X728346Y0I0J3937D01*
G01D02*
Y35433D01*
G01X720079Y47244D02*
G03Y39370I0J-3937D01*
G01Y79528D02*
G03Y71654I0J-3937D01*
G01X723820D02*
Y47244D01*
G01X720079Y71654D02*
X723820D01*
G01Y47244D02*
X720079D01*
G01X740157Y43307D02*
G03X736220Y39370I0J-3937D01*
G01X740157Y43307D02*
X759253D01*
G01X736220Y30315D02*
Y39370D01*
G01X735631Y51181D02*
X759253D01*
G01X731694Y55118D02*
G03X735631Y51181I3937J0D01*
G01X731694Y75591D02*
Y55118D01*
G01X728346Y30315D02*
G03X736220I3937J0D01*
G01X728346Y35433D02*
G03X724409Y39370I-3937J0D01*
G01X747540Y99213D02*
G03X758957I5708J0D01*
G01D02*
G03X747540I-5709J0D01*
G01X731694Y75591D02*
G03X727757Y79528I-3937J0D01*
G01X736220Y134646D02*
G03X740157Y130709I3937J0D01*
G01X771064D02*
X740157D01*
G01X736220Y139764D02*
Y134646D01*
G01X728346Y164961D02*
G03X736220I3937J0D01*
G01Y139764D02*
G03X728346I-3937J0D01*
G01X724409Y130709D02*
G03X728346Y134646I0J3937D01*
G01X736220Y164961D02*
Y174016D01*
G01X728346Y134646D02*
Y170079D01*
G01X720079Y181890D02*
G03Y174016I0J-3937D01*
G01Y214174D02*
G03Y206300I0J-3937D01*
G01X723820D02*
Y181890D01*
G01X720079Y206300D02*
X723820D01*
G01Y181890D02*
X720079D01*
G01X740157Y177953D02*
G03X736220Y174016I0J-3937D01*
G01X740157Y177953D02*
X759253D01*
G01X735631Y185827D02*
X759253D01*
G01X731694Y189764D02*
G03X735631Y185827I3937J0D01*
G01X731694Y210237D02*
Y189764D01*
G01Y210237D02*
G03X727757Y214174I-3937J0D01*
G01X728346Y170079D02*
G03X724409Y174016I-3937J0D01*
G01X747540Y233859D02*
G03X758957I5708J0D01*
G01D02*
G03X747540I-5709J0D01*
G01X720079Y316536D02*
G03Y308662I0J-3937D01*
G01X736220Y269292D02*
G03X740157Y265355I3937J0D01*
G01Y312599D02*
G03X736220Y308662I0J-3937D01*
G01X771064Y265355D02*
X740157D01*
G01X736220Y274410D02*
Y269292D01*
G01X728346Y299607D02*
G03X736220I3937J0D01*
G01Y274410D02*
G03X728346I-3937J0D01*
G01X736220Y299607D02*
Y308662D01*
G01X724409Y265355D02*
G03X728346Y269292I0J3937D01*
G01Y304725D02*
G03X724409Y308662I-3937J0D01*
G01X728346Y269292D02*
Y304725D01*
G01X720079Y348820D02*
G03Y340946I0J-3937D01*
G01X723820D02*
Y316536D01*
G01X720079Y340946D02*
X723820D01*
G01Y316536D02*
X720079D01*
G01X740157Y312599D02*
X759253D01*
G01X735631Y320473D02*
X759253D01*
G01X731694Y324410D02*
G03X735631Y320473I3937J0D01*
G01X731694Y344883D02*
Y324410D01*
G01Y344883D02*
G03X727757Y348820I-3937J0D01*
G01X736220Y403938D02*
G03X740157Y400001I3937J0D01*
G01X771064D02*
X740157D01*
G01X736220Y409056D02*
Y403938D01*
G01X724409Y400001D02*
G03X728346Y403938I0J3937D01*
G01D02*
Y439371D01*
G01X747540Y368505D02*
G03X758957I5708J0D01*
G01D02*
G03X747540I-5709J0D01*
G01X720079Y451182D02*
G03Y443308I0J-3937D01*
G01X723820Y475592D02*
Y451182D01*
G01D02*
X720079D01*
G01X740157Y447245D02*
G03X736220Y443308I0J-3937D01*
G01X740157Y447245D02*
X759253D01*
G01X728346Y434253D02*
G03X736220I3937J0D01*
G01Y409056D02*
G03X728346I-3937J0D01*
G01X736220Y434253D02*
Y443308D01*
G01X728346Y439371D02*
G03X724409Y443308I-3937J0D01*
G01X720079Y483466D02*
G03Y475592I0J-3937D01*
G01D02*
X723820D01*
G01X747540Y503151D02*
G03X758957I5708J0D01*
G01X735631Y455119D02*
X759253D01*
G01X731694Y459056D02*
G03X735631Y455119I3937J0D01*
G01X731694Y479529D02*
Y459056D01*
G01Y479529D02*
G03X727757Y483466I-3937J0D01*
G01X736220Y538584D02*
G03X740157Y534647I3937J0D01*
G01X771064D02*
X740157D01*
G01X736220Y543702D02*
Y538584D01*
G01Y543702D02*
G03X728346I-3937J0D01*
G01X724409Y534647D02*
G03X728346Y538584I0J3937D01*
G01D02*
Y574017D01*
G01X758957Y503151D02*
G03X747540I-5709J0D01*
G01X720079Y585828D02*
G03Y577954I0J-3937D01*
G01X723820Y610238D02*
Y585828D01*
G01D02*
X720079D01*
G01X740157Y581891D02*
G03X736220Y577954I0J-3937D01*
G01X740157Y581891D02*
X759253D01*
G01X728346Y568899D02*
G03X736220I3937J0D01*
G01D02*
Y577954D01*
G01X735631Y589765D02*
X759253D01*
G01X731694Y593702D02*
G03X735631Y589765I3937J0D01*
G01X731694Y614175D02*
Y593702D01*
G01X728346Y574017D02*
G03X724409Y577954I-3937J0D01*
G01X720079Y618112D02*
G03Y610238I0J-3937D01*
G01D02*
X723820D01*
G01X747540Y637797D02*
G03X758957I5708J0D01*
G01D02*
G03X747540I-5709J0D01*
G01X731694Y614175D02*
G03X727757Y618112I-3937J0D01*
G01X736220Y673230D02*
G03X740157Y669293I3937J0D01*
G01X771064D02*
X740157D01*
G01X736220Y678348D02*
Y673230D01*
G01Y678348D02*
G03X728346I-3937J0D01*
G01X724409Y669293D02*
G03X728346Y673230I0J3937D01*
G01D02*
Y708663D01*
G01X720079Y720474D02*
G03Y712600I0J-3937D01*
G01X723820Y744884D02*
Y720474D01*
G01D02*
X720079D01*
G01X740157Y716537D02*
G03X736220Y712600I0J-3937D01*
G01X740157Y716537D02*
X759253D01*
G01X728346Y703545D02*
G03X736220I3937J0D01*
G01D02*
Y712600D01*
G01X735631Y724411D02*
X759253D01*
G01X731694Y728348D02*
G03X735631Y724411I3937J0D01*
G01X731694Y748821D02*
Y728348D01*
G01X728346Y708664D02*
G03X724409Y712601I-3937J0D01*
G01X720079Y752758D02*
G03Y744884I0J-3937D01*
G01D02*
X723820D01*
G01X747540Y772443D02*
G03X758957I5708J0D01*
G01D02*
G03X747540I-5709J0D01*
G01X731694Y748821D02*
G03X727757Y752758I-3937J0D01*
G01X736220Y807876D02*
G03X740157Y803939I3937J0D01*
G01X771064D02*
X740157D01*
G01X736220Y812995D02*
Y807876D01*
G01X728346Y838191D02*
G03X736220I3937J0D01*
G01Y812995D02*
G03X728346I-3937J0D01*
G01X724409Y803939D02*
G03X728346Y807876I0J3937D01*
G01D02*
Y843309D01*
G01X720079Y855120D02*
G03Y847246I0J-3937D01*
G01Y887404D02*
G03Y879530I0J-3937D01*
G01X723820D02*
Y855120D01*
G01X720079Y879530D02*
X723820D01*
G01Y855120D02*
X720079D01*
G01X740157Y851183D02*
G03X736220Y847246I0J-3937D01*
G01X740157Y851183D02*
X759253D01*
G01X736220Y838191D02*
Y847246D01*
G01X735631Y859057D02*
X759253D01*
G01X731694Y862994D02*
G03X735631Y859057I3937J0D01*
G01X731694Y883467D02*
Y862994D01*
G01X728346Y843310D02*
G03X724409Y847247I-3937J0D01*
G01X747540Y907089D02*
G03X758957I5708J0D01*
G01D02*
G03X747540I-5709J0D01*
G01X731694Y883467D02*
G03X727757Y887404I-3937J0D01*
G01X793111Y-3937D02*
G03X800985Y3937I0J7874D01*
G01Y67717D02*
Y3937D01*
G01X789036Y19685D02*
G03I-4291J0D01*
G01X800985Y67717D02*
G03X797048Y71654I-3937J0D01*
G01X771064Y55118D02*
Y71654D01*
G01X796261D02*
X797048D01*
G01X759253Y43307D02*
G03X771064Y55118I0J11811D01*
G01X763190D02*
Y75591D01*
G01X759253Y51181D02*
G03X763190Y55118I0J3937D01*
G01X796261Y79528D02*
G03Y71654I0J-3937D01*
G01X771064D02*
G03Y79528I0J3937D01*
G01X779706Y99213D02*
G03X789784I5039J0D01*
G01D02*
G03X779706I-5039J0D01*
G01X800985Y118898D02*
G03X797048Y122835I-3937J0D01*
G01X800985Y83465D02*
Y118898D01*
G01X797048Y79528D02*
G03X800985Y83465I0J3937D01*
G01X767127Y79528D02*
X797048D01*
G01X767127D02*
G03X763190Y75591I0J-3937D01*
G01X797048Y130709D02*
G03X800985Y134646I0J3937D01*
G01X796261Y130709D02*
X797048D01*
G01X800985Y202363D02*
Y134646D01*
G01X789036Y154331D02*
G03I-4291J0D01*
G01X771064Y122835D02*
G03Y130709I0J3937D01*
G01X796261D02*
G03Y122835I0J-3937D01*
G01X800985Y202363D02*
G03X797048Y206300I-3937J0D01*
G01Y214174D02*
G03X800985Y218111I0J3937D01*
G01X796261Y206300D02*
X797048D01*
G01X767127Y214174D02*
X797048D01*
G01X767127D02*
G03X763190Y210237I0J-3937D01*
G01X771064Y189764D02*
Y206300D01*
G01X763190Y189764D02*
Y210237D01*
G01X759253Y177953D02*
G03X771064Y189764I0J11811D01*
G01X759253Y185827D02*
G03X763190Y189764I0J3937D01*
G01X796261Y214174D02*
G03Y206300I0J-3937D01*
G01X771064D02*
G03Y214174I0J3937D01*
G01Y257481D02*
G03Y265355I0J3937D01*
G01X796261D02*
G03Y257481I0J-3937D01*
G01X779706Y233859D02*
G03X789784I5039J0D01*
G01D02*
G03X779706I-5039J0D01*
G01X800985Y253544D02*
G03X797048Y257481I-3937J0D01*
G01X800985Y218111D02*
Y253544D01*
G01X797048Y265355D02*
G03X800985Y269292I0J3937D01*
G01X796261Y265355D02*
X797048D01*
G01X800985Y337009D02*
Y269292D01*
G01X789036Y288977D02*
G03I-4291J0D01*
G01X800985Y337009D02*
G03X797048Y340946I-3937J0D01*
G01X796261D02*
X797048D01*
G01X771064Y324410D02*
Y340946D01*
G01X759253Y312599D02*
G03X771064Y324410I0J11811D01*
G01X796261Y348820D02*
G03Y340946I0J-3937D01*
G01X771064D02*
G03Y348820I0J3937D01*
G01X800985Y352757D02*
Y388190D01*
G01X797048Y348820D02*
G03X800985Y352757I0J3937D01*
G01X767127Y348820D02*
X797048D01*
G01X767127D02*
G03X763190Y344883I0J-3937D01*
G01Y324410D02*
Y344883D01*
G01X759253Y320473D02*
G03X763190Y324410I0J3937D01*
G01X797048Y400001D02*
G03X800985Y403938I0J3937D01*
G01X796261Y400001D02*
X797048D01*
G01X800985Y471655D02*
Y403938D01*
G01X771064Y392127D02*
G03Y400001I0J3937D01*
G01X796261D02*
G03Y392127I0J-3937D01*
G01X779706Y368505D02*
G03X789784I5039J0D01*
G01D02*
G03X779706I-5039J0D01*
G01X800985Y388190D02*
G03X797048Y392127I-3937J0D01*
G01X759253Y447246D02*
G03X771064Y459057I0J11811D01*
G01X789036Y423623D02*
G03I-4291J0D01*
G01X800985Y471655D02*
G03X797048Y475592I-3937J0D01*
G01X796261D02*
X797048D01*
G01X771064Y459056D02*
Y475592D01*
G01X796261Y483466D02*
G03Y475592I0J-3937D01*
G01X771064D02*
G03Y483466I0J3937D01*
G01X779706Y503151D02*
G03X789784I5039J0D01*
G01X800985Y487403D02*
Y522836D01*
G01X797048Y483466D02*
G03X800985Y487403I0J3937D01*
G01X767127Y483466D02*
X797048D01*
G01X767127D02*
G03X763190Y479529I0J-3937D01*
G01Y459056D02*
Y479529D01*
G01X759253Y455120D02*
G03X763190Y459057I0J3937D01*
G01X797048Y534647D02*
G03X800985Y538584I0J3937D01*
G01X796261Y534647D02*
X797048D01*
G01X800985Y606301D02*
Y538584D01*
G01X771064Y526773D02*
G03Y534647I0J3937D01*
G01X796261D02*
G03Y526773I0J-3937D01*
G01X789784Y503151D02*
G03X779706I-5039J0D01*
G01X800985Y522836D02*
G03X797048Y526773I-3937J0D01*
G01X771064Y593702D02*
Y610238D01*
G01X759253Y581892D02*
G03X771064Y593703I0J11811D01*
G01X789036Y558269D02*
G03I-4291J0D01*
G01X763190Y593702D02*
Y614175D01*
G01X759253Y589766D02*
G03X763190Y593703I0J3937D01*
G01X800985Y606301D02*
G03X797048Y610238I-3937J0D01*
G01X796261D02*
X797048D01*
G01X796261Y618112D02*
G03Y610238I0J-3937D01*
G01X771064D02*
G03Y618112I0J3937D01*
G01X779706Y637797D02*
G03X789784I5039J0D01*
G01D02*
G03X779706I-5039J0D01*
G01X800985Y622049D02*
Y657482D01*
G01X797048Y618112D02*
G03X800985Y622049I0J3937D01*
G01X767127Y618112D02*
X797048D01*
G01X767127D02*
G03X763190Y614175I0J-3937D01*
G01X797048Y669293D02*
G03X800985Y673230I0J3937D01*
G01X796261Y669293D02*
X797048D01*
G01X800985Y740947D02*
Y673230D01*
G01X789036Y692915D02*
G03I-4291J0D01*
G01X771064Y661419D02*
G03Y669293I0J3937D01*
G01X796261D02*
G03Y661419I0J-3937D01*
G01X800985Y657482D02*
G03X797048Y661419I-3937J0D01*
G01X771064Y728348D02*
Y744884D01*
G01X759253Y716538D02*
G03X771064Y728349I0J11811D01*
G01X763190Y728348D02*
Y748821D01*
G01X759253Y724412D02*
G03X763190Y728349I0J3937D01*
G01X800985Y740947D02*
G03X797048Y744884I-3937J0D01*
G01X796261D02*
X797048D01*
G01X796261Y752758D02*
G03Y744884I0J-3937D01*
G01X771064D02*
G03Y752758I0J3937D01*
G01X779706Y772443D02*
G03X789784I5039J0D01*
G01D02*
G03X779706I-5039J0D01*
G01X800985Y756695D02*
Y792128D01*
G01X797048Y752758D02*
G03X800985Y756695I0J3937D01*
G01X767127Y752758D02*
X797048D01*
G01X767127D02*
G03X763190Y748821I0J-3937D01*
G01X800985Y855100D02*
Y807876D01*
G01X797048Y803939D02*
G03X800985Y807876I0J3937D01*
G01X796261Y803939D02*
X797048D01*
G01X789036Y827561D02*
G03I-4291J0D01*
G01X771064Y796065D02*
G03Y803939I0J3937D01*
G01X796261D02*
G03Y796065I0J-3937D01*
G01X800985Y792128D02*
G03X797048Y796065I-3937J0D01*
G01X800985Y862974D02*
G03Y855100I0J-3937D01*
G01Y875593D02*
G03X797048Y879530I-3937J0D01*
G01X800985Y875593D02*
Y862974D01*
G01X796261Y879530D02*
X797048D01*
G01X771064Y862994D02*
Y879530D01*
G01X759253Y851184D02*
G03X771064Y862995I0J11811D01*
G01X796261Y887404D02*
G03Y879530I0J-3937D01*
G01X771064D02*
G03Y887404I0J3937D01*
G01X763190Y862994D02*
Y883467D01*
G01X759253Y859058D02*
G03X763190Y862995I0J3937D01*
G01X779706Y907089D02*
G03X789784I5039J0D01*
G01D02*
G03X779706I-5039J0D01*
G01X800985Y926774D02*
G03X797048Y930711I-3937J0D01*
G01X800985Y891341D02*
Y926774D01*
G01X797048Y887404D02*
G03X800985Y891341I0J3937D01*
G01X767127Y887404D02*
X797048D01*
G01X767127D02*
G03X763190Y883467I0J-3937D01*
G54D14*
X64300Y20100D03*
X135500Y19200D03*
X97200Y20600D03*
X102600D03*
X278574Y21070D03*
X245753Y21617D03*
X409400Y20900D03*
X442500D03*
X535700Y20500D03*
X568800Y20400D03*
X628000Y19800D03*
X661100Y19900D03*
G54D15*
X82000Y9000D03*
X59000Y47800D03*
X58494Y40465D03*
X47800Y51500D03*
X51573Y47700D03*
X96000Y10500D03*
X135300Y9500D03*
X122800Y8800D03*
X228100Y11100D03*
X260600Y13000D03*
X270500Y8900D03*
X306174Y44235D03*
X300613Y46440D03*
X296425Y49468D03*
X300349Y41423D03*
X420600Y9700D03*
X395500Y20500D03*
X420907Y46740D03*
X424263Y37986D03*
X435200Y9600D03*
X431545Y47333D03*
X428151Y42300D03*
X559800Y8900D03*
X547300Y9000D03*
X523900Y20300D03*
X555698Y37934D03*
X552364Y42400D03*
X545084Y41472D03*
X548424Y47100D03*
X582700Y20500D03*
X653620Y8412D03*
X637981Y8316D03*
X676453Y38712D03*
X676576Y44600D03*
X668361Y43924D03*
X672636Y48100D03*
G54D16*
X64300Y25700D03*
X135500Y24800D03*
X97200Y26200D03*
X102600D03*
X278574Y26670D03*
X245753Y27217D03*
X409400Y26500D03*
X442500D03*
X535700Y26100D03*
X568800Y26000D03*
X628000Y25400D03*
X661100Y25500D03*
G54D17*
X146000Y19500D03*
X157000D03*
G54D18*
X149700Y26300D03*
G54D19*
X155300D03*
M02*
